FILE_TYPE=LIBRARY_PARTS;
primitive 'LBG_CORE_QAT_EXT_D','LBG_CORE_QAT_EXT_D_BGA';
  pin
    'CGC_DUT_DETECT_N':
      PIN_NUMBER='(0,0,0,0,0,0,0,C70,0,0,0,0,0,0)';
      BIDIRECTIONAL='TRUE';
      INPUT_LOAD='(-0.01,0.01)';
      OUTPUT_LOAD='(1.0,-1.0)';
    'CLKOUT_ITPXDPN':
      PIN_NUMBER='(A39,0,0,0,0,0,0,0,0,0,0,0,0,0)';
      BIDIRECTIONAL='TRUE';
      INPUT_LOAD='(-0.01,0.01)';
      OUTPUT_LOAD='(1.0,-1.0)';
    'CLKOUT_ITPXDPP':
      PIN_NUMBER='(C39,0,0,0,0,0,0,0,0,0,0,0,0,0)';
      BIDIRECTIONAL='TRUE';
      INPUT_LOAD='(-0.01,0.01)';
      OUTPUT_LOAD='(1.0,-1.0)';
    'CLKOUT_NSSCCAP0N':
      PIN_NUMBER='(A32,0,0,0,0,0,0,0,0,0,0,0,0,0)';
      BIDIRECTIONAL='TRUE';
      INPUT_LOAD='(-0.01,0.01)';
      OUTPUT_LOAD='(1.0,-1.0)';
    'CLKOUT_NSSCCAP0P':
      PIN_NUMBER='(C32,0,0,0,0,0,0,0,0,0,0,0,0,0)';
      BIDIRECTIONAL='TRUE';
      INPUT_LOAD='(-0.01,0.01)';
      OUTPUT_LOAD='(1.0,-1.0)';
    'CLKOUT_NSSCCAP1N':
      PIN_NUMBER='(B38,0,0,0,0,0,0,0,0,0,0,0,0,0)';
      BIDIRECTIONAL='TRUE';
      INPUT_LOAD='(-0.01,0.01)';
      OUTPUT_LOAD='(1.0,-1.0)';
    'CLKOUT_NSSCCAP1P':
      PIN_NUMBER='(D38,0,0,0,0,0,0,0,0,0,0,0,0,0)';
      BIDIRECTIONAL='TRUE';
      INPUT_LOAD='(-0.01,0.01)';
      OUTPUT_LOAD='(1.0,-1.0)';
    'CLKOUT_PLAT0N':
      PIN_NUMBER='(B29,0,0,0,0,0,0,0,0,0,0,0,0,0)';
      BIDIRECTIONAL='TRUE';
      INPUT_LOAD='(-0.01,0.01)';
      OUTPUT_LOAD='(1.0,-1.0)';
    'CLKOUT_PLAT0P':
      PIN_NUMBER='(D29,0,0,0,0,0,0,0,0,0,0,0,0,0)';
      BIDIRECTIONAL='TRUE';
      INPUT_LOAD='(-0.01,0.01)';
      OUTPUT_LOAD='(1.0,-1.0)';
    'CLKOUT_PLAT1N':
      PIN_NUMBER='(B40,0,0,0,0,0,0,0,0,0,0,0,0,0)';
      BIDIRECTIONAL='TRUE';
      INPUT_LOAD='(-0.01,0.01)';
      OUTPUT_LOAD='(1.0,-1.0)';
    'CLKOUT_PLAT1P':
      PIN_NUMBER='(D40,0,0,0,0,0,0,0,0,0,0,0,0,0)';
      BIDIRECTIONAL='TRUE';
      INPUT_LOAD='(-0.01,0.01)';
      OUTPUT_LOAD='(1.0,-1.0)';
    'CLKOUT_SRCN'<15>:
      PIN_NUMBER='(K27,0,0,0,0,0,0,0,0,0,0,0,0,0)';
      BIDIRECTIONAL='TRUE';
      INPUT_LOAD='(-0.01,0.01)';
      OUTPUT_LOAD='(1.0,-1.0)';
    'CLKOUT_SRCN'<14>:
      PIN_NUMBER='(C20,0,0,0,0,0,0,0,0,0,0,0,0,0)';
      BIDIRECTIONAL='TRUE';
      INPUT_LOAD='(-0.01,0.01)';
      OUTPUT_LOAD='(1.0,-1.0)';
    'CLKOUT_SRCN'<13>:
      PIN_NUMBER='(C24,0,0,0,0,0,0,0,0,0,0,0,0,0)';
      BIDIRECTIONAL='TRUE';
      INPUT_LOAD='(-0.01,0.01)';
      OUTPUT_LOAD='(1.0,-1.0)';
    'CLKOUT_SRCN'<12>:
      PIN_NUMBER='(K24,0,0,0,0,0,0,0,0,0,0,0,0,0)';
      BIDIRECTIONAL='TRUE';
      INPUT_LOAD='(-0.01,0.01)';
      OUTPUT_LOAD='(1.0,-1.0)';
    'CLKOUT_SRCN'<11>:
      PIN_NUMBER='(B21,0,0,0,0,0,0,0,0,0,0,0,0,0)';
      BIDIRECTIONAL='TRUE';
      INPUT_LOAD='(-0.01,0.01)';
      OUTPUT_LOAD='(1.0,-1.0)';
    'CLKOUT_SRCN'<10>:
      PIN_NUMBER='(B23,0,0,0,0,0,0,0,0,0,0,0,0,0)';
      BIDIRECTIONAL='TRUE';
      INPUT_LOAD='(-0.01,0.01)';
      OUTPUT_LOAD='(1.0,-1.0)';
    'CLKOUT_SRCN'<9>:
      PIN_NUMBER='(J26,0,0,0,0,0,0,0,0,0,0,0,0,0)';
      BIDIRECTIONAL='TRUE';
      INPUT_LOAD='(-0.01,0.01)';
      OUTPUT_LOAD='(1.0,-1.0)';
    'CLKOUT_SRCN'<8>:
      PIN_NUMBER='(D31,0,0,0,0,0,0,0,0,0,0,0,0,0)';
      BIDIRECTIONAL='TRUE';
      INPUT_LOAD='(-0.01,0.01)';
      OUTPUT_LOAD='(1.0,-1.0)';
    'CLKOUT_SRCN'<7>:
      PIN_NUMBER='(H31,0,0,0,0,0,0,0,0,0,0,0,0,0)';
      BIDIRECTIONAL='TRUE';
      INPUT_LOAD='(-0.01,0.01)';
      OUTPUT_LOAD='(1.0,-1.0)';
    'CLKOUT_SRCN'<6>:
      PIN_NUMBER='(D33,0,0,0,0,0,0,0,0,0,0,0,0,0)';
      BIDIRECTIONAL='TRUE';
      INPUT_LOAD='(-0.01,0.01)';
      OUTPUT_LOAD='(1.0,-1.0)';
    'CLKOUT_SRCN'<5>:
      PIN_NUMBER='(J40,0,0,0,0,0,0,0,0,0,0,0,0,0)';
      BIDIRECTIONAL='TRUE';
      INPUT_LOAD='(-0.01,0.01)';
      OUTPUT_LOAD='(1.0,-1.0)';
    'CLKOUT_SRCN'<4>:
      PIN_NUMBER='(A28,0,0,0,0,0,0,0,0,0,0,0,0,0)';
      BIDIRECTIONAL='TRUE';
      INPUT_LOAD='(-0.01,0.01)';
      OUTPUT_LOAD='(1.0,-1.0)';
    'CLKOUT_SRCN'<3>:
      PIN_NUMBER='(K42,0,0,0,0,0,0,0,0,0,0,0,0,0)';
      BIDIRECTIONAL='TRUE';
      INPUT_LOAD='(-0.01,0.01)';
      OUTPUT_LOAD='(1.0,-1.0)';
    'CLKOUT_SRCN'<2>:
      PIN_NUMBER='(J33,0,0,0,0,0,0,0,0,0,0,0,0,0)';
      BIDIRECTIONAL='TRUE';
      INPUT_LOAD='(-0.01,0.01)';
      OUTPUT_LOAD='(1.0,-1.0)';
    'CLKOUT_SRCN'<1>:
      PIN_NUMBER='(K35,0,0,0,0,0,0,0,0,0,0,0,0,0)';
      BIDIRECTIONAL='TRUE';
      INPUT_LOAD='(-0.01,0.01)';
      OUTPUT_LOAD='(1.0,-1.0)';
    'CLKOUT_SRCN'<0>:
      PIN_NUMBER='(K38,0,0,0,0,0,0,0,0,0,0,0,0,0)';
      BIDIRECTIONAL='TRUE';
      INPUT_LOAD='(-0.01,0.01)';
      OUTPUT_LOAD='(1.0,-1.0)';
    'CLKOUT_SRCP'<15>:
      PIN_NUMBER='(H27,0,0,0,0,0,0,0,0,0,0,0,0,0)';
      BIDIRECTIONAL='TRUE';
      INPUT_LOAD='(-0.01,0.01)';
      OUTPUT_LOAD='(1.0,-1.0)';
    'CLKOUT_SRCP'<14>:
      PIN_NUMBER='(A20,0,0,0,0,0,0,0,0,0,0,0,0,0)';
      BIDIRECTIONAL='TRUE';
      INPUT_LOAD='(-0.01,0.01)';
      OUTPUT_LOAD='(1.0,-1.0)';
    'CLKOUT_SRCP'<13>:
      PIN_NUMBER='(A24,0,0,0,0,0,0,0,0,0,0,0,0,0)';
      BIDIRECTIONAL='TRUE';
      INPUT_LOAD='(-0.01,0.01)';
      OUTPUT_LOAD='(1.0,-1.0)';
    'CLKOUT_SRCP'<12>:
      PIN_NUMBER='(H24,0,0,0,0,0,0,0,0,0,0,0,0,0)';
      BIDIRECTIONAL='TRUE';
      INPUT_LOAD='(-0.01,0.01)';
      OUTPUT_LOAD='(1.0,-1.0)';
    'CLKOUT_SRCP'<11>:
      PIN_NUMBER='(D21,0,0,0,0,0,0,0,0,0,0,0,0,0)';
      BIDIRECTIONAL='TRUE';
      INPUT_LOAD='(-0.01,0.01)';
      OUTPUT_LOAD='(1.0,-1.0)';
    'CLKOUT_SRCP'<10>:
      PIN_NUMBER='(D23,0,0,0,0,0,0,0,0,0,0,0,0,0)';
      BIDIRECTIONAL='TRUE';
      INPUT_LOAD='(-0.01,0.01)';
      OUTPUT_LOAD='(1.0,-1.0)';
    'CLKOUT_SRCP'<9>:
      PIN_NUMBER='(G26,0,0,0,0,0,0,0,0,0,0,0,0,0)';
      BIDIRECTIONAL='TRUE';
      INPUT_LOAD='(-0.01,0.01)';
      OUTPUT_LOAD='(1.0,-1.0)';
    'CLKOUT_SRCP'<8>:
      PIN_NUMBER='(B31,0,0,0,0,0,0,0,0,0,0,0,0,0)';
      BIDIRECTIONAL='TRUE';
      INPUT_LOAD='(-0.01,0.01)';
      OUTPUT_LOAD='(1.0,-1.0)';
    'CLKOUT_SRCP'<7>:
      PIN_NUMBER='(K31,0,0,0,0,0,0,0,0,0,0,0,0,0)';
      BIDIRECTIONAL='TRUE';
      INPUT_LOAD='(-0.01,0.01)';
      OUTPUT_LOAD='(1.0,-1.0)';
    'CLKOUT_SRCP'<6>:
      PIN_NUMBER='(B33,0,0,0,0,0,0,0,0,0,0,0,0,0)';
      BIDIRECTIONAL='TRUE';
      INPUT_LOAD='(-0.01,0.01)';
      OUTPUT_LOAD='(1.0,-1.0)';
    'CLKOUT_SRCP'<5>:
      PIN_NUMBER='(G40,0,0,0,0,0,0,0,0,0,0,0,0,0)';
      BIDIRECTIONAL='TRUE';
      INPUT_LOAD='(-0.01,0.01)';
      OUTPUT_LOAD='(1.0,-1.0)';
    'CLKOUT_SRCP'<4>:
      PIN_NUMBER='(C28,0,0,0,0,0,0,0,0,0,0,0,0,0)';
      BIDIRECTIONAL='TRUE';
      INPUT_LOAD='(-0.01,0.01)';
      OUTPUT_LOAD='(1.0,-1.0)';
    'CLKOUT_SRCP'<3>:
      PIN_NUMBER='(H42,0,0,0,0,0,0,0,0,0,0,0,0,0)';
      BIDIRECTIONAL='TRUE';
      INPUT_LOAD='(-0.01,0.01)';
      OUTPUT_LOAD='(1.0,-1.0)';
    'CLKOUT_SRCP'<2>:
      PIN_NUMBER='(G33,0,0,0,0,0,0,0,0,0,0,0,0,0)';
      BIDIRECTIONAL='TRUE';
      INPUT_LOAD='(-0.01,0.01)';
      OUTPUT_LOAD='(1.0,-1.0)';
    'CLKOUT_SRCP'<1>:
      PIN_NUMBER='(H35,0,0,0,0,0,0,0,0,0,0,0,0,0)';
      BIDIRECTIONAL='TRUE';
      INPUT_LOAD='(-0.01,0.01)';
      OUTPUT_LOAD='(1.0,-1.0)';
    'CLKOUT_SRCP'<0>:
      PIN_NUMBER='(H38,0,0,0,0,0,0,0,0,0,0,0,0,0)';
      BIDIRECTIONAL='TRUE';
      INPUT_LOAD='(-0.01,0.01)';
      OUTPUT_LOAD='(1.0,-1.0)';
    'CLOCKSE_BMCCLK':
      PIN_NUMBER='(BW50,0,0,0,0,0,0,0,0,0,0,0,0,0)';
      BIDIRECTIONAL='TRUE';
      INPUT_LOAD='(-0.01,0.01)';
      OUTPUT_LOAD='(1.0,-1.0)';
    'CLOCKSE_PMSYNCCLK1':
      PIN_NUMBER='(BY51,0,0,0,0,0,0,0,0,0,0,0,0,0)';
      BIDIRECTIONAL='TRUE';
      INPUT_LOAD='(-0.01,0.01)';
      OUTPUT_LOAD='(1.0,-1.0)';
    'CLOCKSE_PMSYNCCLK2':
      PIN_NUMBER='(BV51,0,0,0,0,0,0,0,0,0,0,0,0,0)';
      BIDIRECTIONAL='TRUE';
      INPUT_LOAD='(-0.01,0.01)';
      OUTPUT_LOAD='(1.0,-1.0)';
    'CPU_TRST_N':
      PIN_NUMBER='(0,0,0,0,AT56,0,0,0,0,0,0,0,0,0)';
      BIDIRECTIONAL='TRUE';
      INPUT_LOAD='(-0.01,0.01)';
      OUTPUT_LOAD='(1.0,-1.0)';
    'DMI_RXN'<3>:
      PIN_NUMBER='(0,0,0,C45,0,0,0,0,0,0,0,0,0,0)';
      BIDIRECTIONAL='TRUE';
      INPUT_LOAD='(-0.01,0.01)';
      OUTPUT_LOAD='(1.0,-1.0)';
    'DMI_RXN'<2>:
      PIN_NUMBER='(0,0,0,D44,0,0,0,0,0,0,0,0,0,0)';
      BIDIRECTIONAL='TRUE';
      INPUT_LOAD='(-0.01,0.01)';
      OUTPUT_LOAD='(1.0,-1.0)';
    'DMI_RXN'<1>:
      PIN_NUMBER='(0,0,0,C43,0,0,0,0,0,0,0,0,0,0)';
      BIDIRECTIONAL='TRUE';
      INPUT_LOAD='(-0.01,0.01)';
      OUTPUT_LOAD='(1.0,-1.0)';
    'DMI_RXN'<0>:
      PIN_NUMBER='(0,0,0,D42,0,0,0,0,0,0,0,0,0,0)';
      BIDIRECTIONAL='TRUE';
      INPUT_LOAD='(-0.01,0.01)';
      OUTPUT_LOAD='(1.0,-1.0)';
    'DMI_RXP'<3>:
      PIN_NUMBER='(0,0,0,A45,0,0,0,0,0,0,0,0,0,0)';
      BIDIRECTIONAL='TRUE';
      INPUT_LOAD='(-0.01,0.01)';
      OUTPUT_LOAD='(1.0,-1.0)';
    'DMI_RXP'<2>:
      PIN_NUMBER='(0,0,0,B44,0,0,0,0,0,0,0,0,0,0)';
      BIDIRECTIONAL='TRUE';
      INPUT_LOAD='(-0.01,0.01)';
      OUTPUT_LOAD='(1.0,-1.0)';
    'DMI_RXP'<1>:
      PIN_NUMBER='(0,0,0,A43,0,0,0,0,0,0,0,0,0,0)';
      BIDIRECTIONAL='TRUE';
      INPUT_LOAD='(-0.01,0.01)';
      OUTPUT_LOAD='(1.0,-1.0)';
    'DMI_RXP'<0>:
      PIN_NUMBER='(0,0,0,B42,0,0,0,0,0,0,0,0,0,0)';
      BIDIRECTIONAL='TRUE';
      INPUT_LOAD='(-0.01,0.01)';
      OUTPUT_LOAD='(1.0,-1.0)';
    'DMI_TXN'<3>:
      PIN_NUMBER='(0,0,0,P52,0,0,0,0,0,0,0,0,0,0)';
      BIDIRECTIONAL='TRUE';
      INPUT_LOAD='(-0.01,0.01)';
      OUTPUT_LOAD='(1.0,-1.0)';
    'DMI_TXN'<2>:
      PIN_NUMBER='(0,0,0,K50,0,0,0,0,0,0,0,0,0,0)';
      BIDIRECTIONAL='TRUE';
      INPUT_LOAD='(-0.01,0.01)';
      OUTPUT_LOAD='(1.0,-1.0)';
    'DMI_TXN'<1>:
      PIN_NUMBER='(0,0,0,J48,0,0,0,0,0,0,0,0,0,0)';
      BIDIRECTIONAL='TRUE';
      INPUT_LOAD='(-0.01,0.01)';
      OUTPUT_LOAD='(1.0,-1.0)';
    'DMI_TXN'<0>:
      PIN_NUMBER='(0,0,0,H46,0,0,0,0,0,0,0,0,0,0)';
      BIDIRECTIONAL='TRUE';
      INPUT_LOAD='(-0.01,0.01)';
      OUTPUT_LOAD='(1.0,-1.0)';
    'DMI_TXP'<3>:
      PIN_NUMBER='(0,0,0,N54,0,0,0,0,0,0,0,0,0,0)';
      BIDIRECTIONAL='TRUE';
      INPUT_LOAD='(-0.01,0.01)';
      OUTPUT_LOAD='(1.0,-1.0)';
    'DMI_TXP'<2>:
      PIN_NUMBER='(0,0,0,M52,0,0,0,0,0,0,0,0,0,0)';
      BIDIRECTIONAL='TRUE';
      INPUT_LOAD='(-0.01,0.01)';
      OUTPUT_LOAD='(1.0,-1.0)';
    'DMI_TXP'<1>:
      PIN_NUMBER='(0,0,0,H50,0,0,0,0,0,0,0,0,0,0)';
      BIDIRECTIONAL='TRUE';
      INPUT_LOAD='(-0.01,0.01)';
      OUTPUT_LOAD='(1.0,-1.0)';
    'DMI_TXP'<0>:
      PIN_NUMBER='(0,0,0,K46,0,0,0,0,0,0,0,0,0,0)';
      BIDIRECTIONAL='TRUE';
      INPUT_LOAD='(-0.01,0.01)';
      OUTPUT_LOAD='(1.0,-1.0)';
    'DSW_PWROK':
      PIN_NUMBER='(0,0,0,0,K13,0,0,0,0,0,0,0,0,0)';
      BIDIRECTIONAL='TRUE';
      INPUT_LOAD='(-0.01,0.01)';
      OUTPUT_LOAD='(1.0,-1.0)';
    'EXTCLKN':
      PIN_NUMBER='(0,0,D66,0,0,0,0,0,0,0,0,0,0,0)';
      BIDIRECTIONAL='TRUE';
      INPUT_LOAD='(-0.01,0.01)';
      OUTPUT_LOAD='(1.0,-1.0)';
    'EXTCLKP':
      PIN_NUMBER='(0,0,E67,0,0,0,0,0,0,0,0,0,0,0)';
      BIDIRECTIONAL='TRUE';
      INPUT_LOAD='(-0.01,0.01)';
      OUTPUT_LOAD='(1.0,-1.0)';
    'GPD0':
      PIN_NUMBER='(0,0,0,0,G15,0,0,0,0,0,0,0,0,0)';
      BIDIRECTIONAL='TRUE';
      INPUT_LOAD='(-0.01,0.01)';
      OUTPUT_LOAD='(1.0,-1.0)';
    'GPD10_SLP_S5_N':
      PIN_NUMBER='(0,0,0,0,B14,0,0,0,0,0,0,0,0,0)';
      BIDIRECTIONAL='TRUE';
      INPUT_LOAD='(-0.01,0.01)';
      OUTPUT_LOAD='(1.0,-1.0)';
    'GPD11_GBEPHY':
      PIN_NUMBER='(0,0,0,0,A13,0,0,0,0,0,0,0,0,0)';
      BIDIRECTIONAL='TRUE';
      INPUT_LOAD='(-0.01,0.01)';
      OUTPUT_LOAD='(1.0,-1.0)';
    'GPD1_ACPRESENT':
      PIN_NUMBER='(0,0,0,0,H13,0,0,0,0,0,0,0,0,0)';
      BIDIRECTIONAL='TRUE';
      INPUT_LOAD='(-0.01,0.01)';
      OUTPUT_LOAD='(1.0,-1.0)';
    'GPD2_GBE_WAKE_N':
      PIN_NUMBER='(0,0,0,0,M11,0,0,0,0,0,0,0,0,0)';
      BIDIRECTIONAL='TRUE';
      INPUT_LOAD='(-0.01,0.01)';
      OUTPUT_LOAD='(1.0,-1.0)';
    'GPD3_PWRBTN_N':
      PIN_NUMBER='(0,0,0,0,C15,0,0,0,0,0,0,0,0,0)';
      BIDIRECTIONAL='TRUE';
      INPUT_LOAD='(-0.01,0.01)';
      OUTPUT_LOAD='(1.0,-1.0)';
    'GPD4_SLP_S3_N':
      PIN_NUMBER='(0,0,0,0,D14,0,0,0,0,0,0,0,0,0)';
      BIDIRECTIONAL='TRUE';
      INPUT_LOAD='(-0.01,0.01)';
      OUTPUT_LOAD='(1.0,-1.0)';
    'GPD5_SLP_S4_N':
      PIN_NUMBER='(0,0,0,0,B16,0,0,0,0,0,0,0,0,0)';
      BIDIRECTIONAL='TRUE';
      INPUT_LOAD='(-0.01,0.01)';
      OUTPUT_LOAD='(1.0,-1.0)';
    'GPD6_SLP_A_N':
      PIN_NUMBER='(0,0,0,0,G11,0,0,0,0,0,0,0,0,0)';
      BIDIRECTIONAL='TRUE';
      INPUT_LOAD='(-0.01,0.01)';
      OUTPUT_LOAD='(1.0,-1.0)';
    'GPD7':
      PIN_NUMBER='(0,0,0,0,H9,0,0,0,0,0,0,0,0,0)';
      BIDIRECTIONAL='TRUE';
      INPUT_LOAD='(-0.01,0.01)';
      OUTPUT_LOAD='(1.0,-1.0)';
    'GPD8_SUSCLK':
      PIN_NUMBER='(0,0,0,0,C13,0,0,0,0,0,0,0,0,0)';
      BIDIRECTIONAL='TRUE';
      INPUT_LOAD='(-0.01,0.01)';
      OUTPUT_LOAD='(1.0,-1.0)';
    'GPD9':
      PIN_NUMBER='(0,0,0,0,A15,0,0,0,0,0,0,0,0,0)';
      BIDIRECTIONAL='TRUE';
      INPUT_LOAD='(-0.01,0.01)';
      OUTPUT_LOAD='(1.0,-1.0)';
    'GPIO_RCOMP_1P8_3P3':
      PIN_NUMBER='(0,0,0,0,0,0,0,AM4,0,0,0,0,0,0)';
      BIDIRECTIONAL='TRUE';
      INPUT_LOAD='(-0.01,0.01)';
      OUTPUT_LOAD='(1.0,-1.0)';
    'GPIO_RCOMP_3P3':
      PIN_NUMBER='(0,0,0,0,0,0,BY25,0,0,0,0,0,0,0)';
      BIDIRECTIONAL='TRUE';
      INPUT_LOAD='(-0.01,0.01)';
      OUTPUT_LOAD='(1.0,-1.0)';
    'GPP_A0_RCIN_N_ESPI_ALERT1_N':
      PIN_NUMBER='(0,0,0,0,0,N3,0,0,0,0,0,0,0,0)';
      BIDIRECTIONAL='TRUE';
      INPUT_LOAD='(-0.01,0.01)';
      OUTPUT_LOAD='(1.0,-1.0)';
    'GPP_A10_CLKOUT_LPC1':
      PIN_NUMBER='(0,0,0,0,0,AA4,0,0,0,0,0,0,0,0)';
      BIDIRECTIONAL='TRUE';
      INPUT_LOAD='(-0.01,0.01)';
      OUTPUT_LOAD='(1.0,-1.0)';
    'GPP_A11_PME_N':
      PIN_NUMBER='(0,0,0,0,0,AC2,0,0,0,0,0,0,0,0)';
      BIDIRECTIONAL='TRUE';
      INPUT_LOAD='(-0.01,0.01)';
      OUTPUT_LOAD='(1.0,-1.0)';
    'GPP_A12_BMBUSY_N_SXEXITHLDOFF_N':
      PIN_NUMBER='(0,0,0,0,0,R1,0,0,0,0,0,0,0,0)';
      BIDIRECTIONAL='TRUE';
      INPUT_LOAD='(-0.01,0.01)';
      OUTPUT_LOAD='(1.0,-1.0)';
    'GPP_A13_SUSWARN_N_SUSPWRDNACK':
      PIN_NUMBER='(0,0,0,0,0,T4,0,0,0,0,0,0,0,0)';
      BIDIRECTIONAL='TRUE';
      INPUT_LOAD='(-0.01,0.01)';
      OUTPUT_LOAD='(1.0,-1.0)';
    'GPP_A14_ESPI_RESET_N':
      PIN_NUMBER='(0,0,0,0,0,AB3,0,0,0,0,0,0,0,0)';
      BIDIRECTIONAL='TRUE';
      INPUT_LOAD='(-0.01,0.01)';
      OUTPUT_LOAD='(1.0,-1.0)';
    'GPP_A15_SUSACK_N':
      PIN_NUMBER='(0,0,0,0,0,AC4,0,0,0,0,0,0,0,0)';
      BIDIRECTIONAL='TRUE';
      INPUT_LOAD='(-0.01,0.01)';
      OUTPUT_LOAD='(1.0,-1.0)';
    'GPP_A16_CLKOUT_LPC2':
      PIN_NUMBER='(0,0,0,0,0,T2,0,0,0,0,0,0,0,0)';
      BIDIRECTIONAL='TRUE';
      INPUT_LOAD='(-0.01,0.01)';
      OUTPUT_LOAD='(1.0,-1.0)';
    'GPP_A17':
      PIN_NUMBER='(0,0,0,0,0,AD1,0,0,0,0,0,0,0,0)';
      BIDIRECTIONAL='TRUE';
      INPUT_LOAD='(-0.01,0.01)';
      OUTPUT_LOAD='(1.0,-1.0)';
    'GPP_A18':
      PIN_NUMBER='(0,0,0,0,0,AD3,0,0,0,0,0,0,0,0)';
      BIDIRECTIONAL='TRUE';
      INPUT_LOAD='(-0.01,0.01)';
      OUTPUT_LOAD='(1.0,-1.0)';
    'GPP_A19':
      PIN_NUMBER='(0,0,0,0,0,V3,0,0,0,0,0,0,0,0)';
      BIDIRECTIONAL='TRUE';
      INPUT_LOAD='(-0.01,0.01)';
      OUTPUT_LOAD='(1.0,-1.0)';
    'GPP_A1_LAD0_ESPI_IO0':
      PIN_NUMBER='(0,0,0,0,0,Y3,0,0,0,0,0,0,0,0)';
      BIDIRECTIONAL='TRUE';
      INPUT_LOAD='(-0.01,0.01)';
      OUTPUT_LOAD='(1.0,-1.0)';
    'GPP_A20':
      PIN_NUMBER='(0,0,0,0,0,W4,0,0,0,0,0,0,0,0)';
      BIDIRECTIONAL='TRUE';
      INPUT_LOAD='(-0.01,0.01)';
      OUTPUT_LOAD='(1.0,-1.0)';
    'GPP_A21':
      PIN_NUMBER='(0,0,0,0,0,AE2,0,0,0,0,0,0,0,0)';
      BIDIRECTIONAL='TRUE';
      INPUT_LOAD='(-0.01,0.01)';
      OUTPUT_LOAD='(1.0,-1.0)';
    'GPP_A22':
      PIN_NUMBER='(0,0,0,0,0,AE4,0,0,0,0,0,0,0,0)';
      BIDIRECTIONAL='TRUE';
      INPUT_LOAD='(-0.01,0.01)';
      OUTPUT_LOAD='(1.0,-1.0)';
    'GPP_A23':
      PIN_NUMBER='(0,0,0,0,0,V1,0,0,0,0,0,0,0,0)';
      BIDIRECTIONAL='TRUE';
      INPUT_LOAD='(-0.01,0.01)';
      OUTPUT_LOAD='(1.0,-1.0)';
    'GPP_A2_LAD1_ESPI_IO1':
      PIN_NUMBER='(0,0,0,0,0,N1,0,0,0,0,0,0,0,0)';
      BIDIRECTIONAL='TRUE';
      INPUT_LOAD='(-0.01,0.01)';
      OUTPUT_LOAD='(1.0,-1.0)';
    'GPP_A3_LAD2_ESPI_IO2':
      PIN_NUMBER='(0,0,0,0,0,W2,0,0,0,0,0,0,0,0)';
      BIDIRECTIONAL='TRUE';
      INPUT_LOAD='(-0.01,0.01)';
      OUTPUT_LOAD='(1.0,-1.0)';
    'GPP_A4_LAD3_ESPI_IO3':
      PIN_NUMBER='(0,0,0,0,0,Y1,0,0,0,0,0,0,0,0)';
      BIDIRECTIONAL='TRUE';
      INPUT_LOAD='(-0.01,0.01)';
      OUTPUT_LOAD='(1.0,-1.0)';
    'GPP_A5_LFRAME_N_ESPI_CS0_N':
      PIN_NUMBER='(0,0,0,0,0,P4,0,0,0,0,0,0,0,0)';
      BIDIRECTIONAL='TRUE';
      INPUT_LOAD='(-0.01,0.01)';
      OUTPUT_LOAD='(1.0,-1.0)';
    'GPP_A6_SERIRQ_ESPI_CS1_N':
      PIN_NUMBER='(0,0,0,0,0,P2,0,0,0,0,0,0,0,0)';
      BIDIRECTIONAL='TRUE';
      INPUT_LOAD='(-0.01,0.01)';
      OUTPUT_LOAD='(1.0,-1.0)';
    'GPP_A7_PIRQA_N_ESPI_ALERT0_N':
      PIN_NUMBER='(0,0,0,0,0,AA2,0,0,0,0,0,0,0,0)';
      BIDIRECTIONAL='TRUE';
      INPUT_LOAD='(-0.01,0.01)';
      OUTPUT_LOAD='(1.0,-1.0)';
    'GPP_A8_CLKRUN_N':
      PIN_NUMBER='(0,0,0,0,0,AB1,0,0,0,0,0,0,0,0)';
      BIDIRECTIONAL='TRUE';
      INPUT_LOAD='(-0.01,0.01)';
      OUTPUT_LOAD='(1.0,-1.0)';
    'GPP_A9_CLKOUT_LPC0_ESPI_CLK':
      PIN_NUMBER='(0,0,0,0,0,R3,0,0,0,0,0,0,0,0)';
      BIDIRECTIONAL='TRUE';
      INPUT_LOAD='(-0.01,0.01)';
      OUTPUT_LOAD='(1.0,-1.0)';
    'GPP_B0_CORE_VID0':
      PIN_NUMBER='(0,0,0,0,0,BL7,0,0,0,0,0,0,0,0)';
      BIDIRECTIONAL='TRUE';
      INPUT_LOAD='(-0.01,0.01)';
      OUTPUT_LOAD='(1.0,-1.0)';
    'GPP_B10_SRCCLKREQ5_N':
      PIN_NUMBER='(0,0,0,0,0,BL11,0,0,0,0,0,0,0,0)';
      BIDIRECTIONAL='TRUE';
      INPUT_LOAD='(-0.01,0.01)';
      OUTPUT_LOAD='(1.0,-1.0)';
    'GPP_B11':
      PIN_NUMBER='(0,0,0,0,0,BK9,0,0,0,0,0,0,0,0)';
      BIDIRECTIONAL='TRUE';
      INPUT_LOAD='(-0.01,0.01)';
      OUTPUT_LOAD='(1.0,-1.0)';
    'GPP_B12_GLB_RST_WARN_N':
      PIN_NUMBER='(0,0,0,0,0,BL18,0,0,0,0,0,0,0,0)';
      BIDIRECTIONAL='TRUE';
      INPUT_LOAD='(-0.01,0.01)';
      OUTPUT_LOAD='(1.0,-1.0)';
    'GPP_B13_PLTRST_N':
      PIN_NUMBER='(0,0,0,0,0,BN18,0,0,0,0,0,0,0,0)';
      BIDIRECTIONAL='TRUE';
      INPUT_LOAD='(-0.01,0.01)';
      OUTPUT_LOAD='(1.0,-1.0)';
    'GPP_B14_SPKR':
      PIN_NUMBER='(0,0,0,0,0,BH13,0,0,0,0,0,0,0,0)';
      BIDIRECTIONAL='TRUE';
      INPUT_LOAD='(-0.01,0.01)';
      OUTPUT_LOAD='(1.0,-1.0)';
    'GPP_B15':
      PIN_NUMBER='(0,0,0,0,0,BK13,0,0,0,0,0,0,0,0)';
      BIDIRECTIONAL='TRUE';
      INPUT_LOAD='(-0.01,0.01)';
      OUTPUT_LOAD='(1.0,-1.0)';
    'GPP_B16':
      PIN_NUMBER='(0,0,0,0,0,BG22,0,0,0,0,0,0,0,0)';
      BIDIRECTIONAL='TRUE';
      INPUT_LOAD='(-0.01,0.01)';
      OUTPUT_LOAD='(1.0,-1.0)';
    'GPP_B17':
      PIN_NUMBER='(0,0,0,0,0,BG15,0,0,0,0,0,0,0,0)';
      BIDIRECTIONAL='TRUE';
      INPUT_LOAD='(-0.01,0.01)';
      OUTPUT_LOAD='(1.0,-1.0)';
    'GPP_B18':
      PIN_NUMBER='(0,0,0,0,0,BL15,0,0,0,0,0,0,0,0)';
      BIDIRECTIONAL='TRUE';
      INPUT_LOAD='(-0.01,0.01)';
      OUTPUT_LOAD='(1.0,-1.0)';
    'GPP_B19':
      PIN_NUMBER='(0,0,0,0,0,BK20,0,0,0,0,0,0,0,0)';
      BIDIRECTIONAL='TRUE';
      INPUT_LOAD='(-0.01,0.01)';
      OUTPUT_LOAD='(1.0,-1.0)';
    'GPP_B1_CORE_VID1':
      PIN_NUMBER='(0,0,0,0,0,BH9,0,0,0,0,0,0,0,0)';
      BIDIRECTIONAL='TRUE';
      INPUT_LOAD='(-0.01,0.01)';
      OUTPUT_LOAD='(1.0,-1.0)';
    'GPP_B2':
      PIN_NUMBER='(0,0,0,0,0,BN15,0,0,0,0,0,0,0,0)';
      BIDIRECTIONAL='TRUE';
      INPUT_LOAD='(-0.01,0.01)';
      OUTPUT_LOAD='(1.0,-1.0)';
    'GPP_B20':
      PIN_NUMBER='(0,0,0,0,0,BJ22,0,0,0,0,0,0,0,0)';
      BIDIRECTIONAL='TRUE';
      INPUT_LOAD='(-0.01,0.01)';
      OUTPUT_LOAD='(1.0,-1.0)';
    'GPP_B21':
      PIN_NUMBER='(0,0,0,0,0,BH17,0,0,0,0,0,0,0,0)';
      BIDIRECTIONAL='TRUE';
      INPUT_LOAD='(-0.01,0.01)';
      OUTPUT_LOAD='(1.0,-1.0)';
    'GPP_B22':
      PIN_NUMBER='(0,0,0,0,0,BR17,0,0,0,0,0,0,0,0)';
      BIDIRECTIONAL='TRUE';
      INPUT_LOAD='(-0.01,0.01)';
      OUTPUT_LOAD='(1.0,-1.0)';
    'GPP_B23_MEIE_SML1ALRT_N_PHOT_N':
      PIN_NUMBER='(0,0,0,0,0,BM20,0,0,0,0,0,0,0,0)';
      BIDIRECTIONAL='TRUE';
      INPUT_LOAD='(-0.01,0.01)';
      OUTPUT_LOAD='(1.0,-1.0)';
    'GPP_B3_CPU_GP2':
      PIN_NUMBER='(0,0,0,0,0,BR9,0,0,0,0,0,0,0,0)';
      BIDIRECTIONAL='TRUE';
      INPUT_LOAD='(-0.01,0.01)';
      OUTPUT_LOAD='(1.0,-1.0)';
    'GPP_B4_CPU_GP3':
      PIN_NUMBER='(0,0,0,0,0,BN7,0,0,0,0,0,0,0,0)';
      BIDIRECTIONAL='TRUE';
      INPUT_LOAD='(-0.01,0.01)';
      OUTPUT_LOAD='(1.0,-1.0)';
    'GPP_B5_SRCCLKREQ0_N':
      PIN_NUMBER='(0,0,0,0,0,BK17,0,0,0,0,0,0,0,0)';
      BIDIRECTIONAL='TRUE';
      INPUT_LOAD='(-0.01,0.01)';
      OUTPUT_LOAD='(1.0,-1.0)';
    'GPP_B6_SRCCLKREQ1_N':
      PIN_NUMBER='(0,0,0,0,0,BG18,0,0,0,0,0,0,0,0)';
      BIDIRECTIONAL='TRUE';
      INPUT_LOAD='(-0.01,0.01)';
      OUTPUT_LOAD='(1.0,-1.0)';
    'GPP_B7_SRCCLKREQ2_N':
      PIN_NUMBER='(0,0,0,0,0,BR13,0,0,0,0,0,0,0,0)';
      BIDIRECTIONAL='TRUE';
      INPUT_LOAD='(-0.01,0.01)';
      OUTPUT_LOAD='(1.0,-1.0)';
    'GPP_B8_SRCCLKREQ3_N':
      PIN_NUMBER='(0,0,0,0,0,BN11,0,0,0,0,0,0,0,0)';
      BIDIRECTIONAL='TRUE';
      INPUT_LOAD='(-0.01,0.01)';
      OUTPUT_LOAD='(1.0,-1.0)';
    'GPP_B9_SRCCLKREQ4_N':
      PIN_NUMBER='(0,0,0,0,0,BH20,0,0,0,0,0,0,0,0)';
      BIDIRECTIONAL='TRUE';
      INPUT_LOAD='(-0.01,0.01)';
      OUTPUT_LOAD='(1.0,-1.0)';
    'GPP_C0_SMBCLK':
      PIN_NUMBER='(0,0,0,0,0,BW28,0,0,0,0,0,0,0,0)';
      BIDIRECTIONAL='TRUE';
      INPUT_LOAD='(-0.01,0.01)';
      OUTPUT_LOAD='(1.0,-1.0)';
    'GPP_C10':
      PIN_NUMBER='(0,0,0,0,0,BV31,0,0,0,0,0,0,0,0)';
      BIDIRECTIONAL='TRUE';
      INPUT_LOAD='(-0.01,0.01)';
      OUTPUT_LOAD='(1.0,-1.0)';
    'GPP_C11':
      PIN_NUMBER='(0,0,0,0,0,BV33,0,0,0,0,0,0,0,0)';
      BIDIRECTIONAL='TRUE';
      INPUT_LOAD='(-0.01,0.01)';
      OUTPUT_LOAD='(1.0,-1.0)';
    'GPP_C12':
      PIN_NUMBER='(0,0,0,0,0,CA30,0,0,0,0,0,0,0,0)';
      BIDIRECTIONAL='TRUE';
      INPUT_LOAD='(-0.01,0.01)';
      OUTPUT_LOAD='(1.0,-1.0)';
    'GPP_C13':
      PIN_NUMBER='(0,0,0,0,0,BV38,0,0,0,0,0,0,0,0)';
      BIDIRECTIONAL='TRUE';
      INPUT_LOAD='(-0.01,0.01)';
      OUTPUT_LOAD='(1.0,-1.0)';
    'GPP_C14':
      PIN_NUMBER='(0,0,0,0,0,BY38,0,0,0,0,0,0,0,0)';
      BIDIRECTIONAL='TRUE';
      INPUT_LOAD='(-0.01,0.01)';
      OUTPUT_LOAD='(1.0,-1.0)';
    'GPP_C15':
      PIN_NUMBER='(0,0,0,0,0,CA32,0,0,0,0,0,0,0,0)';
      BIDIRECTIONAL='TRUE';
      INPUT_LOAD='(-0.01,0.01)';
      OUTPUT_LOAD='(1.0,-1.0)';
    'GPP_C16':
      PIN_NUMBER='(0,0,0,0,0,BW37,0,0,0,0,0,0,0,0)';
      BIDIRECTIONAL='TRUE';
      INPUT_LOAD='(-0.01,0.01)';
      OUTPUT_LOAD='(1.0,-1.0)';
    'GPP_C17':
      PIN_NUMBER='(0,0,0,0,0,BY31,0,0,0,0,0,0,0,0)';
      BIDIRECTIONAL='TRUE';
      INPUT_LOAD='(-0.01,0.01)';
      OUTPUT_LOAD='(1.0,-1.0)';
    'GPP_C18':
      PIN_NUMBER='(0,0,0,0,0,BY35,0,0,0,0,0,0,0,0)';
      BIDIRECTIONAL='TRUE';
      INPUT_LOAD='(-0.01,0.01)';
      OUTPUT_LOAD='(1.0,-1.0)';
    'GPP_C19':
      PIN_NUMBER='(0,0,0,0,0,BW39,0,0,0,0,0,0,0,0)';
      BIDIRECTIONAL='TRUE';
      INPUT_LOAD='(-0.01,0.01)';
      OUTPUT_LOAD='(1.0,-1.0)';
    'GPP_C1_SMBDATA':
      PIN_NUMBER='(0,0,0,0,0,BV27,0,0,0,0,0,0,0,0)';
      BIDIRECTIONAL='TRUE';
      INPUT_LOAD='(-0.01,0.01)';
      OUTPUT_LOAD='(1.0,-1.0)';
    'GPP_C20':
      PIN_NUMBER='(0,0,0,0,0,CA39,0,0,0,0,0,0,0,0)';
      BIDIRECTIONAL='TRUE';
      INPUT_LOAD='(-0.01,0.01)';
      OUTPUT_LOAD='(1.0,-1.0)';
    'GPP_C21':
      PIN_NUMBER='(0,0,0,0,0,BY33,0,0,0,0,0,0,0,0)';
      BIDIRECTIONAL='TRUE';
      INPUT_LOAD='(-0.01,0.01)';
      OUTPUT_LOAD='(1.0,-1.0)';
    'GPP_C22':
      PIN_NUMBER='(0,0,0,0,0,CA34,0,0,0,0,0,0,0,0)';
      BIDIRECTIONAL='TRUE';
      INPUT_LOAD='(-0.01,0.01)';
      OUTPUT_LOAD='(1.0,-1.0)';
    'GPP_C23':
      PIN_NUMBER='(0,0,0,0,0,CA37,0,0,0,0,0,0,0,0)';
      BIDIRECTIONAL='TRUE';
      INPUT_LOAD='(-0.01,0.01)';
      OUTPUT_LOAD='(1.0,-1.0)';
    'GPP_C2_SMBALERT_N':
      PIN_NUMBER='(0,0,0,0,0,BY27,0,0,0,0,0,0,0,0)';
      BIDIRECTIONAL='TRUE';
      INPUT_LOAD='(-0.01,0.01)';
      OUTPUT_LOAD='(1.0,-1.0)';
    'GPP_C3_SML0CLK_IE':
      PIN_NUMBER='(0,0,0,0,0,BV29,0,0,0,0,0,0,0,0)';
      BIDIRECTIONAL='TRUE';
      INPUT_LOAD='(-0.01,0.01)';
      OUTPUT_LOAD='(1.0,-1.0)';
    'GPP_C4_SML0DATA_IE':
      PIN_NUMBER='(0,0,0,0,0,BW30,0,0,0,0,0,0,0,0)';
      BIDIRECTIONAL='TRUE';
      INPUT_LOAD='(-0.01,0.01)';
      OUTPUT_LOAD='(1.0,-1.0)';
    'GPP_C5_SML0ALERT_IE_N':
      PIN_NUMBER='(0,0,0,0,0,BW34,0,0,0,0,0,0,0,0)';
      BIDIRECTIONAL='TRUE';
      INPUT_LOAD='(-0.01,0.01)';
      OUTPUT_LOAD='(1.0,-1.0)';
    'GPP_C6_SML1CLK_IE':
      PIN_NUMBER='(0,0,0,0,0,CA28,0,0,0,0,0,0,0,0)';
      BIDIRECTIONAL='TRUE';
      INPUT_LOAD='(-0.01,0.01)';
      OUTPUT_LOAD='(1.0,-1.0)';
    'GPP_C7_SML1DATA_IE':
      PIN_NUMBER='(0,0,0,0,0,BV35,0,0,0,0,0,0,0,0)';
      BIDIRECTIONAL='TRUE';
      INPUT_LOAD='(-0.01,0.01)';
      OUTPUT_LOAD='(1.0,-1.0)';
    'GPP_C8':
      PIN_NUMBER='(0,0,0,0,0,BW32,0,0,0,0,0,0,0,0)';
      BIDIRECTIONAL='TRUE';
      INPUT_LOAD='(-0.01,0.01)';
      OUTPUT_LOAD='(1.0,-1.0)';
    'GPP_C9':
      PIN_NUMBER='(0,0,0,0,0,BY29,0,0,0,0,0,0,0,0)';
      BIDIRECTIONAL='TRUE';
      INPUT_LOAD='(-0.01,0.01)';
      OUTPUT_LOAD='(1.0,-1.0)';
    'GPP_D0':
      PIN_NUMBER='(0,0,0,0,0,BR42,0,0,0,0,0,0,0,0)';
      BIDIRECTIONAL='TRUE';
      INPUT_LOAD='(-0.01,0.01)';
      OUTPUT_LOAD='(1.0,-1.0)';
    'GPP_D1':
      PIN_NUMBER='(0,0,0,0,0,BK46,0,0,0,0,0,0,0,0)';
      BIDIRECTIONAL='TRUE';
      INPUT_LOAD='(-0.01,0.01)';
      OUTPUT_LOAD='(1.0,-1.0)';
    'GPP_D10_SSATA_DEVSLP4':
      PIN_NUMBER='(0,0,0,0,0,BV47,0,0,0,0,0,0,0,0)';
      BIDIRECTIONAL='TRUE';
      INPUT_LOAD='(-0.01,0.01)';
      OUTPUT_LOAD='(1.0,-1.0)';
    'GPP_D11_SSATA_DEVSLP5':
      PIN_NUMBER='(0,0,0,0,0,BY47,0,0,0,0,0,0,0,0)';
      BIDIRECTIONAL='TRUE';
      INPUT_LOAD='(-0.01,0.01)';
      OUTPUT_LOAD='(1.0,-1.0)';
    'GPP_D12_SSATA_SDATAOUT1':
      PIN_NUMBER='(0,0,0,0,0,BN40,0,0,0,0,0,0,0,0)';
      BIDIRECTIONAL='TRUE';
      INPUT_LOAD='(-0.01,0.01)';
      OUTPUT_LOAD='(1.0,-1.0)';
    'GPP_D13_SML0BCLK_IE':
      PIN_NUMBER='(0,0,0,0,0,BY44,0,0,0,0,0,0,0,0)';
      BIDIRECTIONAL='TRUE';
      INPUT_LOAD='(-0.01,0.01)';
      OUTPUT_LOAD='(1.0,-1.0)';
    'GPP_D14_SML0BDATA_IE':
      PIN_NUMBER='(0,0,0,0,0,BL44,0,0,0,0,0,0,0,0)';
      BIDIRECTIONAL='TRUE';
      INPUT_LOAD='(-0.01,0.01)';
      OUTPUT_LOAD='(1.0,-1.0)';
    'GPP_D15_SSATA_SDATAOUT0':
      PIN_NUMBER='(0,0,0,0,0,BW43,0,0,0,0,0,0,0,0)';
      BIDIRECTIONAL='TRUE';
      INPUT_LOAD='(-0.01,0.01)';
      OUTPUT_LOAD='(1.0,-1.0)';
    'GPP_D16_SML0BALERT_IE_N':
      PIN_NUMBER='(0,0,0,0,0,BV42,0,0,0,0,0,0,0,0)';
      BIDIRECTIONAL='TRUE';
      INPUT_LOAD='(-0.01,0.01)';
      OUTPUT_LOAD='(1.0,-1.0)';
    'GPP_D17':
      PIN_NUMBER='(0,0,0,0,0,BW48,0,0,0,0,0,0,0,0)';
      BIDIRECTIONAL='TRUE';
      INPUT_LOAD='(-0.01,0.01)';
      OUTPUT_LOAD='(1.0,-1.0)';
    'GPP_D18':
      PIN_NUMBER='(0,0,0,0,0,CA41,0,0,0,0,0,0,0,0)';
      BIDIRECTIONAL='TRUE';
      INPUT_LOAD='(-0.01,0.01)';
      OUTPUT_LOAD='(1.0,-1.0)';
    'GPP_D19':
      PIN_NUMBER='(0,0,0,0,0,CA43,0,0,0,0,0,0,0,0)';
      BIDIRECTIONAL='TRUE';
      INPUT_LOAD='(-0.01,0.01)';
      OUTPUT_LOAD='(1.0,-1.0)';
    'GPP_D2':
      PIN_NUMBER='(0,0,0,0,0,BJ44,0,0,0,0,0,0,0,0)';
      BIDIRECTIONAL='TRUE';
      INPUT_LOAD='(-0.01,0.01)';
      OUTPUT_LOAD='(1.0,-1.0)';
    'GPP_D20':
      PIN_NUMBER='(0,0,0,0,0,CA48,0,0,0,0,0,0,0,0)';
      BIDIRECTIONAL='TRUE';
      INPUT_LOAD='(-0.01,0.01)';
      OUTPUT_LOAD='(1.0,-1.0)';
    'GPP_D21_IE_UART_RX':
      PIN_NUMBER='(0,0,0,0,0,BV44,0,0,0,0,0,0,0,0)';
      BIDIRECTIONAL='TRUE';
      INPUT_LOAD='(-0.01,0.01)';
      OUTPUT_LOAD='(1.0,-1.0)';
    'GPP_D22_IE_UART_TX':
      PIN_NUMBER='(0,0,0,0,0,BR46,0,0,0,0,0,0,0,0)';
      BIDIRECTIONAL='TRUE';
      INPUT_LOAD='(-0.01,0.01)';
      OUTPUT_LOAD='(1.0,-1.0)';
    'GPP_D23':
      PIN_NUMBER='(0,0,0,0,0,BN44,0,0,0,0,0,0,0,0)';
      BIDIRECTIONAL='TRUE';
      INPUT_LOAD='(-0.01,0.01)';
      OUTPUT_LOAD='(1.0,-1.0)';
    'GPP_D3':
      PIN_NUMBER='(0,0,0,0,0,BW45,0,0,0,0,0,0,0,0)';
      BIDIRECTIONAL='TRUE';
      INPUT_LOAD='(-0.01,0.01)';
      OUTPUT_LOAD='(1.0,-1.0)';
    'GPP_D4':
      PIN_NUMBER='(0,0,0,0,0,BM42,0,0,0,0,0,0,0,0)';
      BIDIRECTIONAL='TRUE';
      INPUT_LOAD='(-0.01,0.01)';
      OUTPUT_LOAD='(1.0,-1.0)';
    'GPP_D5':
      PIN_NUMBER='(0,0,0,0,0,BM38,0,0,0,0,0,0,0,0)';
      BIDIRECTIONAL='TRUE';
      INPUT_LOAD='(-0.01,0.01)';
      OUTPUT_LOAD='(1.0,-1.0)';
    'GPP_D6':
      PIN_NUMBER='(0,0,0,0,0,BW41,0,0,0,0,0,0,0,0)';
      BIDIRECTIONAL='TRUE';
      INPUT_LOAD='(-0.01,0.01)';
      OUTPUT_LOAD='(1.0,-1.0)';
    'GPP_D7':
      PIN_NUMBER='(0,0,0,0,0,CA45,0,0,0,0,0,0,0,0)';
      BIDIRECTIONAL='TRUE';
      INPUT_LOAD='(-0.01,0.01)';
      OUTPUT_LOAD='(1.0,-1.0)';
    'GPP_D8':
      PIN_NUMBER='(0,0,0,0,0,BR38,0,0,0,0,0,0,0,0)';
      BIDIRECTIONAL='TRUE';
      INPUT_LOAD='(-0.01,0.01)';
      OUTPUT_LOAD='(1.0,-1.0)';
    'GPP_D9_SSATA_DEVSLP3':
      PIN_NUMBER='(0,0,0,0,0,BY42,0,0,0,0,0,0,0,0)';
      BIDIRECTIONAL='TRUE';
      INPUT_LOAD='(-0.01,0.01)';
      OUTPUT_LOAD='(1.0,-1.0)';
    'GPP_E0_SATAXPCIE0_SATAGP0':
      PIN_NUMBER='(0,0,0,0,0,0,BH50,0,0,0,0,0,0,0)';
      BIDIRECTIONAL='TRUE';
      INPUT_LOAD='(-0.01,0.01)';
      OUTPUT_LOAD='(1.0,-1.0)';
    'GPP_E10_USB2_OC1_N':
      PIN_NUMBER='(0,0,0,0,0,0,BN48,0,0,0,0,0,0,0)';
      BIDIRECTIONAL='TRUE';
      INPUT_LOAD='(-0.01,0.01)';
      OUTPUT_LOAD='(1.0,-1.0)';
    'GPP_E11_USB2_OC2_N':
      PIN_NUMBER='(0,0,0,0,0,0,AW54,0,0,0,0,0,0,0)';
      BIDIRECTIONAL='TRUE';
      INPUT_LOAD='(-0.01,0.01)';
      OUTPUT_LOAD='(1.0,-1.0)';
    'GPP_E12_USB2_OC3_N':
      PIN_NUMBER='(0,0,0,0,0,0,AU58,0,0,0,0,0,0,0)';
      BIDIRECTIONAL='TRUE';
      INPUT_LOAD='(-0.01,0.01)';
      OUTPUT_LOAD='(1.0,-1.0)';
    'GPP_E1_SATAXPCIE1_SATAGP1':
      PIN_NUMBER='(0,0,0,0,0,0,AY52,0,0,0,0,0,0,0)';
      BIDIRECTIONAL='TRUE';
      INPUT_LOAD='(-0.01,0.01)';
      OUTPUT_LOAD='(1.0,-1.0)';
    'GPP_E2_SATAXPCIE2_SATAGP2':
      PIN_NUMBER='(0,0,0,0,0,0,BG52,0,0,0,0,0,0,0)';
      BIDIRECTIONAL='TRUE';
      INPUT_LOAD='(-0.01,0.01)';
      OUTPUT_LOAD='(1.0,-1.0)';
    'GPP_E3_CPU_GP0':
      PIN_NUMBER='(0,0,0,0,0,0,BE52,0,0,0,0,0,0,0)';
      BIDIRECTIONAL='TRUE';
      INPUT_LOAD='(-0.01,0.01)';
      OUTPUT_LOAD='(1.0,-1.0)';
    'GPP_E4_SATA_DEVSLP0':
      PIN_NUMBER='(0,0,0,0,0,0,AV52,0,0,0,0,0,0,0)';
      BIDIRECTIONAL='TRUE';
      INPUT_LOAD='(-0.01,0.01)';
      OUTPUT_LOAD='(1.0,-1.0)';
    'GPP_E5_SATA_DEVSLP1':
      PIN_NUMBER='(0,0,0,0,0,0,AT52,0,0,0,0,0,0,0)';
      BIDIRECTIONAL='TRUE';
      INPUT_LOAD='(-0.01,0.01)';
      OUTPUT_LOAD='(1.0,-1.0)';
    'GPP_E6_SATA_DEVSLP2':
      PIN_NUMBER='(0,0,0,0,0,0,BB52,0,0,0,0,0,0,0)';
      BIDIRECTIONAL='TRUE';
      INPUT_LOAD='(-0.01,0.01)';
      OUTPUT_LOAD='(1.0,-1.0)';
    'GPP_E7_CPU_GP1':
      PIN_NUMBER='(0,0,0,0,0,0,BJ48,0,0,0,0,0,0,0)';
      BIDIRECTIONAL='TRUE';
      INPUT_LOAD='(-0.01,0.01)';
      OUTPUT_LOAD='(1.0,-1.0)';
    'GPP_E8_SATA_LED_N':
      PIN_NUMBER='(0,0,0,0,0,0,AV56,0,0,0,0,0,0,0)';
      BIDIRECTIONAL='TRUE';
      INPUT_LOAD='(-0.01,0.01)';
      OUTPUT_LOAD='(1.0,-1.0)';
    'GPP_E9_USB2_OC0_N':
      PIN_NUMBER='(0,0,0,0,0,0,BL48,0,0,0,0,0,0,0)';
      BIDIRECTIONAL='TRUE';
      INPUT_LOAD='(-0.01,0.01)';
      OUTPUT_LOAD='(1.0,-1.0)';
    'GPP_F0_SATAXPCIE3_SATAGP3':
      PIN_NUMBER='(0,0,0,0,0,0,AG7,0,0,0,0,0,0,0)';
      BIDIRECTIONAL='TRUE';
      INPUT_LOAD='(-0.01,0.01)';
      OUTPUT_LOAD='(1.0,-1.0)';
    'GPP_F10_SATA_SCLOCK':
      PIN_NUMBER='(0,0,0,0,0,0,AL7,0,0,0,0,0,0,0)';
      BIDIRECTIONAL='TRUE';
      INPUT_LOAD='(-0.01,0.01)';
      OUTPUT_LOAD='(1.0,-1.0)';
    'GPP_F11_SATA_SLOAD':
      PIN_NUMBER='(0,0,0,0,0,0,AR9,0,0,0,0,0,0,0)';
      BIDIRECTIONAL='TRUE';
      INPUT_LOAD='(-0.01,0.01)';
      OUTPUT_LOAD='(1.0,-1.0)';
    'GPP_F12_SATA_SDATAOUT1':
      PIN_NUMBER='(0,0,0,0,0,0,AP7,0,0,0,0,0,0,0)';
      BIDIRECTIONAL='TRUE';
      INPUT_LOAD='(-0.01,0.01)';
      OUTPUT_LOAD='(1.0,-1.0)';
    'GPP_F13_SATA_SDATAOUT0':
      PIN_NUMBER='(0,0,0,0,0,0,AP11,0,0,0,0,0,0,0)';
      BIDIRECTIONAL='TRUE';
      INPUT_LOAD='(-0.01,0.01)';
      OUTPUT_LOAD='(1.0,-1.0)';
    'GPP_F14_SSATA_LED_N':
      PIN_NUMBER='(0,0,0,0,0,0,AL11,0,0,0,0,0,0,0)';
      BIDIRECTIONAL='TRUE';
      INPUT_LOAD='(-0.01,0.01)';
      OUTPUT_LOAD='(1.0,-1.0)';
    'GPP_F15_USB2_OC4_N':
      PIN_NUMBER='(0,0,0,0,0,0,AR13,0,0,0,0,0,0,0)';
      BIDIRECTIONAL='TRUE';
      INPUT_LOAD='(-0.01,0.01)';
      OUTPUT_LOAD='(1.0,-1.0)';
    'GPP_F16_USB2_OC5_N':
      PIN_NUMBER='(0,0,0,0,0,0,AU13,0,0,0,0,0,0,0)';
      BIDIRECTIONAL='TRUE';
      INPUT_LOAD='(-0.01,0.01)';
      OUTPUT_LOAD='(1.0,-1.0)';
    'GPP_F17_USB2_OC6_N':
      PIN_NUMBER='(0,0,0,0,0,0,AP15,0,0,0,0,0,0,0)';
      BIDIRECTIONAL='TRUE';
      INPUT_LOAD='(-0.01,0.01)';
      OUTPUT_LOAD='(1.0,-1.0)';
    'GPP_F18_USB2_OC7_N':
      PIN_NUMBER='(0,0,0,0,0,0,AL15,0,0,0,0,0,0,0)';
      BIDIRECTIONAL='TRUE';
      INPUT_LOAD='(-0.01,0.01)';
      OUTPUT_LOAD='(1.0,-1.0)';
    'GPP_F19_LAN_SMBCLK':
      PIN_NUMBER='(0,0,0,0,0,0,AU9,0,0,0,0,0,0,0)';
      BIDIRECTIONAL='TRUE';
      INPUT_LOAD='(-0.01,0.01)';
      OUTPUT_LOAD='(1.0,-1.0)';
    'GPP_F1_SATAXPCIE4_SATAGP4':
      PIN_NUMBER='(0,0,0,0,0,0,AK9,0,0,0,0,0,0,0)';
      BIDIRECTIONAL='TRUE';
      INPUT_LOAD='(-0.01,0.01)';
      OUTPUT_LOAD='(1.0,-1.0)';
    'GPP_F20_LAN_SMBDATA':
      PIN_NUMBER='(0,0,0,0,0,0,AU20,0,0,0,0,0,0,0)';
      BIDIRECTIONAL='TRUE';
      INPUT_LOAD='(-0.01,0.01)';
      OUTPUT_LOAD='(1.0,-1.0)';
    'GPP_F21_LAN_SMBALRT_N':
      PIN_NUMBER='(0,0,0,0,0,0,AR17,0,0,0,0,0,0,0)';
      BIDIRECTIONAL='TRUE';
      INPUT_LOAD='(-0.01,0.01)';
      OUTPUT_LOAD='(1.0,-1.0)';
    'GPP_F22_SSATA_SCLOCK':
      PIN_NUMBER='(0,0,0,0,0,0,AP18,0,0,0,0,0,0,0)';
      BIDIRECTIONAL='TRUE';
      INPUT_LOAD='(-0.01,0.01)';
      OUTPUT_LOAD='(1.0,-1.0)';
    'GPP_F23_SSATA_SLOAD':
      PIN_NUMBER='(0,0,0,0,0,0,AU17,0,0,0,0,0,0,0)';
      BIDIRECTIONAL='TRUE';
      INPUT_LOAD='(-0.01,0.01)';
      OUTPUT_LOAD='(1.0,-1.0)';
    'GPP_F2_SATAXPCIE5_SATAGP5':
      PIN_NUMBER='(0,0,0,0,0,0,AK20,0,0,0,0,0,0,0)';
      BIDIRECTIONAL='TRUE';
      INPUT_LOAD='(-0.01,0.01)';
      OUTPUT_LOAD='(1.0,-1.0)';
    'GPP_F3_SATAXPCIE6_SATAGP6':
      PIN_NUMBER='(0,0,0,0,0,0,AK13,0,0,0,0,0,0,0)';
      BIDIRECTIONAL='TRUE';
      INPUT_LOAD='(-0.01,0.01)';
      OUTPUT_LOAD='(1.0,-1.0)';
    'GPP_F4_SATAXPCIE7_SATAGP7':
      PIN_NUMBER='(0,0,0,0,0,0,AH13,0,0,0,0,0,0,0)';
      BIDIRECTIONAL='TRUE';
      INPUT_LOAD='(-0.01,0.01)';
      OUTPUT_LOAD='(1.0,-1.0)';
    'GPP_F5_SATA_DEVSLP3':
      PIN_NUMBER='(0,0,0,0,0,0,AH17,0,0,0,0,0,0,0)';
      BIDIRECTIONAL='TRUE';
      INPUT_LOAD='(-0.01,0.01)';
      OUTPUT_LOAD='(1.0,-1.0)';
    'GPP_F6_SATA_DEVSLP4':
      PIN_NUMBER='(0,0,0,0,0,0,AL18,0,0,0,0,0,0,0)';
      BIDIRECTIONAL='TRUE';
      INPUT_LOAD='(-0.01,0.01)';
      OUTPUT_LOAD='(1.0,-1.0)';
    'GPP_F7_SATA_DEVSLP5':
      PIN_NUMBER='(0,0,0,0,0,0,AK17,0,0,0,0,0,0,0)';
      BIDIRECTIONAL='TRUE';
      INPUT_LOAD='(-0.01,0.01)';
      OUTPUT_LOAD='(1.0,-1.0)';
    'GPP_F8_SATA_DEVSLP6':
      PIN_NUMBER='(0,0,0,0,0,0,AH9,0,0,0,0,0,0,0)';
      BIDIRECTIONAL='TRUE';
      INPUT_LOAD='(-0.01,0.01)';
      OUTPUT_LOAD='(1.0,-1.0)';
    'GPP_F9_SATA_DEVSLP7':
      PIN_NUMBER='(0,0,0,0,0,0,AR20,0,0,0,0,0,0,0)';
      BIDIRECTIONAL='TRUE';
      INPUT_LOAD='(-0.01,0.01)';
      OUTPUT_LOAD='(1.0,-1.0)';
    'GPP_G0_FANTACH0_FANTACH0IE':
      PIN_NUMBER='(0,0,0,0,0,0,AY11,0,0,0,0,0,0,0)';
      BIDIRECTIONAL='TRUE';
      INPUT_LOAD='(-0.01,0.01)';
      OUTPUT_LOAD='(1.0,-1.0)';
    'GPP_G10_FANPWM2_FANPWM2IE':
      PIN_NUMBER='(0,0,0,0,0,0,BE11,0,0,0,0,0,0,0)';
      BIDIRECTIONAL='TRUE';
      INPUT_LOAD='(-0.01,0.01)';
      OUTPUT_LOAD='(1.0,-1.0)';
    'GPP_G11_FANPWM3_FANPMW3IE':
      PIN_NUMBER='(0,0,0,0,0,0,BA20,0,0,0,0,0,0,0)';
      BIDIRECTIONAL='TRUE';
      INPUT_LOAD='(-0.01,0.01)';
      OUTPUT_LOAD='(1.0,-1.0)';
    'GPP_G12':
      PIN_NUMBER='(0,0,0,0,0,0,BD13,0,0,0,0,0,0,0)';
      BIDIRECTIONAL='TRUE';
      INPUT_LOAD='(-0.01,0.01)';
      OUTPUT_LOAD='(1.0,-1.0)';
    'GPP_G13':
      PIN_NUMBER='(0,0,0,0,0,0,AY18,0,0,0,0,0,0,0)';
      BIDIRECTIONAL='TRUE';
      INPUT_LOAD='(-0.01,0.01)';
      OUTPUT_LOAD='(1.0,-1.0)';
    'GPP_G14':
      PIN_NUMBER='(0,0,0,0,0,0,AV7,0,0,0,0,0,0,0)';
      BIDIRECTIONAL='TRUE';
      INPUT_LOAD='(-0.01,0.01)';
      OUTPUT_LOAD='(1.0,-1.0)';
    'GPP_G15':
      PIN_NUMBER='(0,0,0,0,0,0,BE18,0,0,0,0,0,0,0)';
      BIDIRECTIONAL='TRUE';
      INPUT_LOAD='(-0.01,0.01)';
      OUTPUT_LOAD='(1.0,-1.0)';
    'GPP_G16':
      PIN_NUMBER='(0,0,0,0,0,0,BD17,0,0,0,0,0,0,0)';
      BIDIRECTIONAL='TRUE';
      INPUT_LOAD='(-0.01,0.01)';
      OUTPUT_LOAD='(1.0,-1.0)';
    'GPP_G17_ADR_COMPLETE':
      PIN_NUMBER='(0,0,0,0,0,0,BD9,0,0,0,0,0,0,0)';
      BIDIRECTIONAL='TRUE';
      INPUT_LOAD='(-0.01,0.01)';
      OUTPUT_LOAD='(1.0,-1.0)';
    'GPP_G18_NMI_N':
      PIN_NUMBER='(0,0,0,0,0,0,BE7,0,0,0,0,0,0,0)';
      BIDIRECTIONAL='TRUE';
      INPUT_LOAD='(-0.01,0.01)';
      OUTPUT_LOAD='(1.0,-1.0)';
    'GPP_G19_SMI_N':
      PIN_NUMBER='(0,0,0,0,0,0,BE15,0,0,0,0,0,0,0)';
      BIDIRECTIONAL='TRUE';
      INPUT_LOAD='(-0.01,0.01)';
      OUTPUT_LOAD='(1.0,-1.0)';
    'GPP_G1_FANTACH1_FANTACH1IE':
      PIN_NUMBER='(0,0,0,0,0,0,AV15,0,0,0,0,0,0,0)';
      BIDIRECTIONAL='TRUE';
      INPUT_LOAD='(-0.01,0.01)';
      OUTPUT_LOAD='(1.0,-1.0)';
    'GPP_G20_SSATA_DEVSLP0':
      PIN_NUMBER='(0,0,0,0,0,0,BA17,0,0,0,0,0,0,0)';
      BIDIRECTIONAL='TRUE';
      INPUT_LOAD='(-0.01,0.01)';
      OUTPUT_LOAD='(1.0,-1.0)';
    'GPP_G21_SSATA_DEVSLP1':
      PIN_NUMBER='(0,0,0,0,0,0,BG7,0,0,0,0,0,0,0)';
      BIDIRECTIONAL='TRUE';
      INPUT_LOAD='(-0.01,0.01)';
      OUTPUT_LOAD='(1.0,-1.0)';
    'GPP_G22_SSATA_DEVSLP2':
      PIN_NUMBER='(0,0,0,0,0,0,BD20,0,0,0,0,0,0,0)';
      BIDIRECTIONAL='TRUE';
      INPUT_LOAD='(-0.01,0.01)';
      OUTPUT_LOAD='(1.0,-1.0)';
    'GPP_G23_SSATAXPCIE0_SSATAGP0':
      PIN_NUMBER='(0,0,0,0,0,0,BA13,0,0,0,0,0,0,0)';
      BIDIRECTIONAL='TRUE';
      INPUT_LOAD='(-0.01,0.01)';
      OUTPUT_LOAD='(1.0,-1.0)';
    'GPP_G2_FANTACH2_FANTACH2IE':
      PIN_NUMBER='(0,0,0,0,0,0,BE22,0,0,0,0,0,0,0)';
      BIDIRECTIONAL='TRUE';
      INPUT_LOAD='(-0.01,0.01)';
      OUTPUT_LOAD='(1.0,-1.0)';
    'GPP_G3_FANTACH3_FANTACH3IE':
      PIN_NUMBER='(0,0,0,0,0,0,AY7,0,0,0,0,0,0,0)';
      BIDIRECTIONAL='TRUE';
      INPUT_LOAD='(-0.01,0.01)';
      OUTPUT_LOAD='(1.0,-1.0)';
    'GPP_G4_FANTACH4_FANTACH4IE':
      PIN_NUMBER='(0,0,0,0,0,0,BA9,0,0,0,0,0,0,0)';
      BIDIRECTIONAL='TRUE';
      INPUT_LOAD='(-0.01,0.01)';
      OUTPUT_LOAD='(1.0,-1.0)';
    'GPP_G5_FANTACH5_FANTACH5IE':
      PIN_NUMBER='(0,0,0,0,0,0,AW20,0,0,0,0,0,0,0)';
      BIDIRECTIONAL='TRUE';
      INPUT_LOAD='(-0.01,0.01)';
      OUTPUT_LOAD='(1.0,-1.0)';
    'GPP_G6_FANTACH6_FANTACH6IE':
      PIN_NUMBER='(0,0,0,0,0,0,AV18,0,0,0,0,0,0,0)';
      BIDIRECTIONAL='TRUE';
      INPUT_LOAD='(-0.01,0.01)';
      OUTPUT_LOAD='(1.0,-1.0)';
    'GPP_G7_FANTACH7_FANTACH7IE':
      PIN_NUMBER='(0,0,0,0,0,0,AY15,0,0,0,0,0,0,0)';
      BIDIRECTIONAL='TRUE';
      INPUT_LOAD='(-0.01,0.01)';
      OUTPUT_LOAD='(1.0,-1.0)';
    'GPP_G8_FANPWM0_FANPWM0IE':
      PIN_NUMBER='(0,0,0,0,0,0,BG11,0,0,0,0,0,0,0)';
      BIDIRECTIONAL='TRUE';
      INPUT_LOAD='(-0.01,0.01)';
      OUTPUT_LOAD='(1.0,-1.0)';
    'GPP_G9_FANPWM1_FAMPWM1IE':
      PIN_NUMBER='(0,0,0,0,0,0,AV11,0,0,0,0,0,0,0)';
      BIDIRECTIONAL='TRUE';
      INPUT_LOAD='(-0.01,0.01)';
      OUTPUT_LOAD='(1.0,-1.0)';
    'GPP_H0_SRCCLKREQ6_N':
      PIN_NUMBER='(0,0,0,0,0,0,AT4,0,0,0,0,0,0,0)';
      BIDIRECTIONAL='TRUE';
      INPUT_LOAD='(-0.01,0.01)';
      OUTPUT_LOAD='(1.0,-1.0)';
    'GPP_H10_SML2CLK_IE':
      PIN_NUMBER='(0,0,0,0,0,0,BA4,0,0,0,0,0,0,0)';
      BIDIRECTIONAL='TRUE';
      INPUT_LOAD='(-0.01,0.01)';
      OUTPUT_LOAD='(1.0,-1.0)';
    'GPP_H11_SML2DATA_IE':
      PIN_NUMBER='(0,0,0,0,0,0,BD1,0,0,0,0,0,0,0)';
      BIDIRECTIONAL='TRUE';
      INPUT_LOAD='(-0.01,0.01)';
      OUTPUT_LOAD='(1.0,-1.0)';
    'GPP_H12_SML2ALERT_N_IE_N':
      PIN_NUMBER='(0,0,0,0,0,0,BB1,0,0,0,0,0,0,0)';
      BIDIRECTIONAL='TRUE';
      INPUT_LOAD='(-0.01,0.01)';
      OUTPUT_LOAD='(1.0,-1.0)';
    'GPP_H13_SML3CLK_IE':
      PIN_NUMBER='(0,0,0,0,0,0,AY1,0,0,0,0,0,0,0)';
      BIDIRECTIONAL='TRUE';
      INPUT_LOAD='(-0.01,0.01)';
      OUTPUT_LOAD='(1.0,-1.0)';
    'GPP_H14_SML3DATA_IE':
      PIN_NUMBER='(0,0,0,0,0,0,BC2,0,0,0,0,0,0,0)';
      BIDIRECTIONAL='TRUE';
      INPUT_LOAD='(-0.01,0.01)';
      OUTPUT_LOAD='(1.0,-1.0)';
    'GPP_H15_SML3ALERT_N_IE_N':
      PIN_NUMBER='(0,0,0,0,0,0,BB3,0,0,0,0,0,0,0)';
      BIDIRECTIONAL='TRUE';
      INPUT_LOAD='(-0.01,0.01)';
      OUTPUT_LOAD='(1.0,-1.0)';
    'GPP_H16_SML4CLK_IE':
      PIN_NUMBER='(0,0,0,0,0,0,BF1,0,0,0,0,0,0,0)';
      BIDIRECTIONAL='TRUE';
      INPUT_LOAD='(-0.01,0.01)';
      OUTPUT_LOAD='(1.0,-1.0)';
    'GPP_H17_SML4DATA_IE':
      PIN_NUMBER='(0,0,0,0,0,0,BE4,0,0,0,0,0,0,0)';
      BIDIRECTIONAL='TRUE';
      INPUT_LOAD='(-0.01,0.01)';
      OUTPUT_LOAD='(1.0,-1.0)';
    'GPP_H18_SML4ALERT_N_IE_N':
      PIN_NUMBER='(0,0,0,0,0,0,BC4,0,0,0,0,0,0,0)';
      BIDIRECTIONAL='TRUE';
      INPUT_LOAD='(-0.01,0.01)';
      OUTPUT_LOAD='(1.0,-1.0)';
    'GPP_H19_SSATAXPCIE1_SSATAGP1':
      PIN_NUMBER='(0,0,0,0,0,0,BD3,0,0,0,0,0,0,0)';
      BIDIRECTIONAL='TRUE';
      INPUT_LOAD='(-0.01,0.01)';
      OUTPUT_LOAD='(1.0,-1.0)';
    'GPP_H1_SRCCLKREQ7_N':
      PIN_NUMBER='(0,0,0,0,0,0,AW4,0,0,0,0,0,0,0)';
      BIDIRECTIONAL='TRUE';
      INPUT_LOAD='(-0.01,0.01)';
      OUTPUT_LOAD='(1.0,-1.0)';
    'GPP_H20_SSATAXPCIE2_SSATAGP2':
      PIN_NUMBER='(0,0,0,0,0,0,BF3,0,0,0,0,0,0,0)';
      BIDIRECTIONAL='TRUE';
      INPUT_LOAD='(-0.01,0.01)';
      OUTPUT_LOAD='(1.0,-1.0)';
    'GPP_H21_SSATAXPCIE3_SSATAGP3':
      PIN_NUMBER='(0,0,0,0,0,0,BA2,0,0,0,0,0,0,0)';
      BIDIRECTIONAL='TRUE';
      INPUT_LOAD='(-0.01,0.01)';
      OUTPUT_LOAD='(1.0,-1.0)';
    'GPP_H22_SSATAXPCIE4_SSATAGP4':
      PIN_NUMBER='(0,0,0,0,0,0,BH2,0,0,0,0,0,0,0)';
      BIDIRECTIONAL='TRUE';
      INPUT_LOAD='(-0.01,0.01)';
      OUTPUT_LOAD='(1.0,-1.0)';
    'GPP_H23_SSATAXPCIE5_SSATAGP5':
      PIN_NUMBER='(0,0,0,0,0,0,BH4,0,0,0,0,0,0,0)';
      BIDIRECTIONAL='TRUE';
      INPUT_LOAD='(-0.01,0.01)';
      OUTPUT_LOAD='(1.0,-1.0)';
    'GPP_H2_SRCCLKREQ8_N':
      PIN_NUMBER='(0,0,0,0,0,0,AV3,0,0,0,0,0,0,0)';
      BIDIRECTIONAL='TRUE';
      INPUT_LOAD='(-0.01,0.01)';
      OUTPUT_LOAD='(1.0,-1.0)';
    'GPP_H3_SRCCLKREQ9_N':
      PIN_NUMBER='(0,0,0,0,0,0,AR1,0,0,0,0,0,0,0)';
      BIDIRECTIONAL='TRUE';
      INPUT_LOAD='(-0.01,0.01)';
      OUTPUT_LOAD='(1.0,-1.0)';
    'GPP_H4_SRCCLKREQ10_N':
      PIN_NUMBER='(0,0,0,0,0,0,AT2,0,0,0,0,0,0,0)';
      BIDIRECTIONAL='TRUE';
      INPUT_LOAD='(-0.01,0.01)';
      OUTPUT_LOAD='(1.0,-1.0)';
    'GPP_H5_SRCCLKREQ11_N':
      PIN_NUMBER='(0,0,0,0,0,0,AY3,0,0,0,0,0,0,0)';
      BIDIRECTIONAL='TRUE';
      INPUT_LOAD='(-0.01,0.01)';
      OUTPUT_LOAD='(1.0,-1.0)';
    'GPP_H6_SRCCLKREQ12_N':
      PIN_NUMBER='(0,0,0,0,0,0,AW2,0,0,0,0,0,0,0)';
      BIDIRECTIONAL='TRUE';
      INPUT_LOAD='(-0.01,0.01)';
      OUTPUT_LOAD='(1.0,-1.0)';
    'GPP_H7_SRCCLKREQ13_N':
      PIN_NUMBER='(0,0,0,0,0,0,AV1,0,0,0,0,0,0,0)';
      BIDIRECTIONAL='TRUE';
      INPUT_LOAD='(-0.01,0.01)';
      OUTPUT_LOAD='(1.0,-1.0)';
    'GPP_H8_SRCCLKREQ14_N':
      PIN_NUMBER='(0,0,0,0,0,0,AR3,0,0,0,0,0,0,0)';
      BIDIRECTIONAL='TRUE';
      INPUT_LOAD='(-0.01,0.01)';
      OUTPUT_LOAD='(1.0,-1.0)';
    'GPP_H9_SRCCLKREQ15_N':
      PIN_NUMBER='(0,0,0,0,0,0,BE2,0,0,0,0,0,0,0)';
      BIDIRECTIONAL='TRUE';
      INPUT_LOAD='(-0.01,0.01)';
      OUTPUT_LOAD='(1.0,-1.0)';
    'GPP_I0_LAN_TDO':
      PIN_NUMBER='(0,0,0,0,0,0,CA20,0,0,0,0,0,0,0)';
      PINUSE='UNSPEC';
      NO_LOAD_CHECK='Both';
      NO_IO_CHECK='Both';
      NO_ASSERT_CHECK='TRUE';
      NO_DIR_CHECK='TRUE';
      ALLOW_CONNECT='TRUE';
    'GPP_I10':
      PIN_NUMBER='(0,0,0,0,0,0,BV25,0,0,0,0,0,0,0)';
      BIDIRECTIONAL='TRUE';
      INPUT_LOAD='(-0.01,0.01)';
      OUTPUT_LOAD='(1.0,-1.0)';
    'GPP_I1_LAN_TCK':
      PIN_NUMBER='(0,0,0,0,0,0,BV21,0,0,0,0,0,0,0)';
      PINUSE='UNSPEC';
      NO_LOAD_CHECK='Both';
      NO_IO_CHECK='Both';
      NO_ASSERT_CHECK='TRUE';
      NO_DIR_CHECK='TRUE';
      ALLOW_CONNECT='TRUE';
    'GPP_I2_LAN_TMS':
      PIN_NUMBER='(0,0,0,0,0,0,CA22,0,0,0,0,0,0,0)';
      PINUSE='UNSPEC';
      NO_LOAD_CHECK='Both';
      NO_IO_CHECK='Both';
      NO_ASSERT_CHECK='TRUE';
      NO_DIR_CHECK='TRUE';
      ALLOW_CONNECT='TRUE';
    'GPP_I3_LAN_TDI':
      PIN_NUMBER='(0,0,0,0,0,0,BY23,0,0,0,0,0,0,0)';
      PINUSE='UNSPEC';
      NO_LOAD_CHECK='Both';
      NO_IO_CHECK='Both';
      NO_ASSERT_CHECK='TRUE';
      NO_DIR_CHECK='TRUE';
      ALLOW_CONNECT='TRUE';
    'GPP_I4_DO_RESET_IN_N':
      PIN_NUMBER='(0,0,0,0,0,0,BW20,0,0,0,0,0,0,0)';
      BIDIRECTIONAL='TRUE';
      INPUT_LOAD='(-0.01,0.01)';
      OUTPUT_LOAD='(1.0,-1.0)';
    'GPP_I5_DO_RESET_OUT_N':
      PIN_NUMBER='(0,0,0,0,0,0,BW24,0,0,0,0,0,0,0)';
      BIDIRECTIONAL='TRUE';
      INPUT_LOAD='(-0.01,0.01)';
      OUTPUT_LOAD='(1.0,-1.0)';
    'GPP_I6_RESET_DONE':
      PIN_NUMBER='(0,0,0,0,0,0,BV23,0,0,0,0,0,0,0)';
      BIDIRECTIONAL='TRUE';
      INPUT_LOAD='(-0.01,0.01)';
      OUTPUT_LOAD='(1.0,-1.0)';
    'GPP_I7_LAN_TRST_N':
      PIN_NUMBER='(0,0,0,0,0,0,CA24,0,0,0,0,0,0,0)';
      PINUSE='UNSPEC';
      NO_LOAD_CHECK='Both';
      NO_IO_CHECK='Both';
      NO_ASSERT_CHECK='TRUE';
      NO_DIR_CHECK='TRUE';
      ALLOW_CONNECT='TRUE';
    'GPP_I8_PCI_DIS_N':
      PIN_NUMBER='(0,0,0,0,0,0,BW22,0,0,0,0,0,0,0)';
      PINUSE='UNSPEC';
      NO_LOAD_CHECK='Both';
      NO_IO_CHECK='Both';
      NO_ASSERT_CHECK='TRUE';
      NO_DIR_CHECK='TRUE';
      ALLOW_CONNECT='TRUE';
    'GPP_I9_LAN_DIS_N':
      PIN_NUMBER='(0,0,0,0,0,0,BY21,0,0,0,0,0,0,0)';
      PINUSE='UNSPEC';
      NO_LOAD_CHECK='Both';
      NO_IO_CHECK='Both';
      NO_ASSERT_CHECK='TRUE';
      NO_DIR_CHECK='TRUE';
      ALLOW_CONNECT='TRUE';
    'GPP_J0_LAN_LED_P0_0':
      PIN_NUMBER='(0,0,0,0,0,0,BL1,0,0,0,0,0,0,0)';
      BIDIRECTIONAL='TRUE';
      INPUT_LOAD='(-0.01,0.01)';
      OUTPUT_LOAD='(1.0,-1.0)';
    'GPP_J10_LAN_I2C_SCL_MDC_P1':
      PIN_NUMBER='(0,0,0,0,0,0,BW5,0,0,0,0,0,0,0)';
      BIDIRECTIONAL='TRUE';
      INPUT_LOAD='(-0.01,0.01)';
      OUTPUT_LOAD='(1.0,-1.0)';
    'GPP_J11_LAN_I2C_SDA_MDIO_P1':
      PIN_NUMBER='(0,0,0,0,0,0,BV8,0,0,0,0,0,0,0)';
      BIDIRECTIONAL='TRUE';
      INPUT_LOAD='(-0.01,0.01)';
      OUTPUT_LOAD='(1.0,-1.0)';
    'GPP_J12_LAN_I2C_SCL_MDC_P2':
      PIN_NUMBER='(0,0,0,0,0,0,BT5,0,0,0,0,0,0,0)';
      BIDIRECTIONAL='TRUE';
      INPUT_LOAD='(-0.01,0.01)';
      OUTPUT_LOAD='(1.0,-1.0)';
    'GPP_J13_LAN_I2C_SDA_MDIO_P2':
      PIN_NUMBER='(0,0,0,0,0,0,BW11,0,0,0,0,0,0,0)';
      BIDIRECTIONAL='TRUE';
      INPUT_LOAD='(-0.01,0.01)';
      OUTPUT_LOAD='(1.0,-1.0)';
    'GPP_J14_LAN_I2C_SCL_MDC_P3':
      PIN_NUMBER='(0,0,0,0,0,0,BW6,0,0,0,0,0,0,0)';
      BIDIRECTIONAL='TRUE';
      INPUT_LOAD='(-0.01,0.01)';
      OUTPUT_LOAD='(1.0,-1.0)';
    'GPP_J15_LAN_I2C_SDA_MDIO_P3':
      PIN_NUMBER='(0,0,0,0,0,0,BW9,0,0,0,0,0,0,0)';
      BIDIRECTIONAL='TRUE';
      INPUT_LOAD='(-0.01,0.01)';
      OUTPUT_LOAD='(1.0,-1.0)';
    'GPP_J16_LAN_SDP_P0_0':
      PIN_NUMBER='(0,0,0,0,0,0,BV10,0,0,0,0,0,0,0)';
      BIDIRECTIONAL='TRUE';
      INPUT_LOAD='(-0.01,0.01)';
      OUTPUT_LOAD='(1.0,-1.0)';
    'GPP_J17_LAN_SDP_P0_1':
      PIN_NUMBER='(0,0,0,0,0,0,CA11,0,0,0,0,0,0,0)';
      BIDIRECTIONAL='TRUE';
      INPUT_LOAD='(-0.01,0.01)';
      OUTPUT_LOAD='(1.0,-1.0)';
    'GPP_J18_LAN_SDP_P1_0':
      PIN_NUMBER='(0,0,0,0,0,0,BY10,0,0,0,0,0,0,0)';
      BIDIRECTIONAL='TRUE';
      INPUT_LOAD='(-0.01,0.01)';
      OUTPUT_LOAD='(1.0,-1.0)';
    'GPP_J19_LAN_SDP_P1_1':
      PIN_NUMBER='(0,0,0,0,0,0,BY14,0,0,0,0,0,0,0)';
      BIDIRECTIONAL='TRUE';
      INPUT_LOAD='(-0.01,0.01)';
      OUTPUT_LOAD='(1.0,-1.0)';
    'GPP_J1_LAN_LED_P0_1':
      PIN_NUMBER='(0,0,0,0,0,0,BK4,0,0,0,0,0,0,0)';
      BIDIRECTIONAL='TRUE';
      INPUT_LOAD='(-0.01,0.01)';
      OUTPUT_LOAD='(1.0,-1.0)';
    'GPP_J20_LAN_SDP_P2_0':
      PIN_NUMBER='(0,0,0,0,0,0,BW13,0,0,0,0,0,0,0)';
      BIDIRECTIONAL='TRUE';
      INPUT_LOAD='(-0.01,0.01)';
      OUTPUT_LOAD='(1.0,-1.0)';
    'GPP_J21_LAN_SDP_P2_1':
      PIN_NUMBER='(0,0,0,0,0,0,BV12,0,0,0,0,0,0,0)';
      BIDIRECTIONAL='TRUE';
      INPUT_LOAD='(-0.01,0.01)';
      OUTPUT_LOAD='(1.0,-1.0)';
    'GPP_J22_LAN_SDP_P3_0':
      PIN_NUMBER='(0,0,0,0,0,0,BY12,0,0,0,0,0,0,0)';
      BIDIRECTIONAL='TRUE';
      INPUT_LOAD='(-0.01,0.01)';
      OUTPUT_LOAD='(1.0,-1.0)';
    'GPP_J23_LAN_SDP_P3_1':
      PIN_NUMBER='(0,0,0,0,0,0,BV14,0,0,0,0,0,0,0)';
      BIDIRECTIONAL='TRUE';
      INPUT_LOAD='(-0.01,0.01)';
      OUTPUT_LOAD='(1.0,-1.0)';
    'GPP_J2_LAN_LED_P1_0':
      PIN_NUMBER='(0,0,0,0,0,0,BP4,0,0,0,0,0,0,0)';
      BIDIRECTIONAL='TRUE';
      INPUT_LOAD='(-0.01,0.01)';
      OUTPUT_LOAD='(1.0,-1.0)';
    'GPP_J3_LAN_LED_P1_1':
      PIN_NUMBER='(0,0,0,0,0,0,BK2,0,0,0,0,0,0,0)';
      BIDIRECTIONAL='TRUE';
      INPUT_LOAD='(-0.01,0.01)';
      OUTPUT_LOAD='(1.0,-1.0)';
    'GPP_J4_LAN_LED_P2_0':
      PIN_NUMBER='(0,0,0,0,0,0,BL3,0,0,0,0,0,0,0)';
      BIDIRECTIONAL='TRUE';
      INPUT_LOAD='(-0.01,0.01)';
      OUTPUT_LOAD='(1.0,-1.0)';
    'GPP_J5_LAN_LED_P2_1':
      PIN_NUMBER='(0,0,0,0,0,0,BU6,0,0,0,0,0,0,0)';
      BIDIRECTIONAL='TRUE';
      INPUT_LOAD='(-0.01,0.01)';
      OUTPUT_LOAD='(1.0,-1.0)';
    'GPP_J6_LAN_LED_P3_0':
      PIN_NUMBER='(0,0,0,0,0,0,CA13,0,0,0,0,0,0,0)';
      BIDIRECTIONAL='TRUE';
      INPUT_LOAD='(-0.01,0.01)';
      OUTPUT_LOAD='(1.0,-1.0)';
    'GPP_J7_LAN_LED_P3_1':
      PIN_NUMBER='(0,0,0,0,0,0,BM2,0,0,0,0,0,0,0)';
      BIDIRECTIONAL='TRUE';
      INPUT_LOAD='(-0.01,0.01)';
      OUTPUT_LOAD='(1.0,-1.0)';
    'GPP_J8_LAN_I2C_SCL_MDC_P0':
      PIN_NUMBER='(0,0,0,0,0,0,BM4,0,0,0,0,0,0,0)';
      BIDIRECTIONAL='TRUE';
      INPUT_LOAD='(-0.01,0.01)';
      OUTPUT_LOAD='(1.0,-1.0)';
    'GPP_J9_LAN_I2C_SDA_MDIO_P0':
      PIN_NUMBER='(0,0,0,0,0,0,BN3,0,0,0,0,0,0,0)';
      BIDIRECTIONAL='TRUE';
      INPUT_LOAD='(-0.01,0.01)';
      OUTPUT_LOAD='(1.0,-1.0)';
    'GPP_K0_LAN_NCSI_CLK_IN':
      PIN_NUMBER='(0,0,0,0,0,0,0,AJ1,0,0,0,0,0,0)';
      BIDIRECTIONAL='TRUE';
      INPUT_LOAD='(-0.01,0.01)';
      OUTPUT_LOAD='(1.0,-1.0)';
    'GPP_K10_PE_RST_N':
      PIN_NUMBER='(0,0,0,0,0,0,0,AH4,0,0,0,0,0,0)';
      BIDIRECTIONAL='TRUE';
      INPUT_LOAD='(-0.01,0.01)';
      OUTPUT_LOAD='(1.0,-1.0)';
    'GPP_K1_LAN_NCSI_TXD0':
      PIN_NUMBER='(0,0,0,0,0,0,0,AM2,0,0,0,0,0,0)';
      BIDIRECTIONAL='TRUE';
      INPUT_LOAD='(-0.01,0.01)';
      OUTPUT_LOAD='(1.0,-1.0)';
    'GPP_K2_LAN_NCSI_TXD1':
      PIN_NUMBER='(0,0,0,0,0,0,0,AK2,0,0,0,0,0,0)';
      BIDIRECTIONAL='TRUE';
      INPUT_LOAD='(-0.01,0.01)';
      OUTPUT_LOAD='(1.0,-1.0)';
    'GPP_K3_LAN_NCSI_TX_EN':
      PIN_NUMBER='(0,0,0,0,0,0,0,AL3,0,0,0,0,0,0)';
      BIDIRECTIONAL='TRUE';
      INPUT_LOAD='(-0.01,0.01)';
      OUTPUT_LOAD='(1.0,-1.0)';
    'GPP_K4_LAN_NCSI_CRS_DV':
      PIN_NUMBER='(0,0,0,0,0,0,0,AN3,0,0,0,0,0,0)';
      BIDIRECTIONAL='TRUE';
      INPUT_LOAD='(-0.01,0.01)';
      OUTPUT_LOAD='(1.0,-1.0)';
    'GPP_K5_LAN_NCSI_RXD0':
      PIN_NUMBER='(0,0,0,0,0,0,0,AL1,0,0,0,0,0,0)';
      BIDIRECTIONAL='TRUE';
      INPUT_LOAD='(-0.01,0.01)';
      OUTPUT_LOAD='(1.0,-1.0)';
    'GPP_K6_LAN_NCSI_RXD1':
      PIN_NUMBER='(0,0,0,0,0,0,0,AN1,0,0,0,0,0,0)';
      BIDIRECTIONAL='TRUE';
      INPUT_LOAD='(-0.01,0.01)';
      OUTPUT_LOAD='(1.0,-1.0)';
    'GPP_K7':
      PIN_NUMBER='(0,0,0,0,0,0,0,AH2,0,0,0,0,0,0)';
      BIDIRECTIONAL='TRUE';
      INPUT_LOAD='(-0.01,0.01)';
      OUTPUT_LOAD='(1.0,-1.0)';
    'GPP_K8_LAN_NCSI_ARB_IN':
      PIN_NUMBER='(0,0,0,0,0,0,0,AJ3,0,0,0,0,0,0)';
      BIDIRECTIONAL='TRUE';
      INPUT_LOAD='(-0.01,0.01)';
      OUTPUT_LOAD='(1.0,-1.0)';
    'GPP_K9_LAN_NCSI_ARB_OUT':
      PIN_NUMBER='(0,0,0,0,0,0,0,AK4,0,0,0,0,0,0)';
      BIDIRECTIONAL='TRUE';
      INPUT_LOAD='(-0.01,0.01)';
      OUTPUT_LOAD='(1.0,-1.0)';
    'GPP_L10_TESTCH0_CLK':
      PIN_NUMBER='(0,0,0,0,0,0,0,AF20,0,0,0,0,0,0)';
      BIDIRECTIONAL='TRUE';
      INPUT_LOAD='(-0.01,0.01)';
      OUTPUT_LOAD='(1.0,-1.0)';
    'GPP_L11_TESTCH1_D0':
      PIN_NUMBER='(0,0,0,0,0,0,0,AD20,0,0,0,0,0,0)';
      BIDIRECTIONAL='TRUE';
      INPUT_LOAD='(-0.01,0.01)';
      OUTPUT_LOAD='(1.0,-1.0)';
    'GPP_L12_TESTCH1_D1':
      PIN_NUMBER='(0,0,0,0,0,0,0,Y15,0,0,0,0,0,0)';
      BIDIRECTIONAL='TRUE';
      INPUT_LOAD='(-0.01,0.01)';
      OUTPUT_LOAD='(1.0,-1.0)';
    'GPP_L13_TESTCH1_D2':
      PIN_NUMBER='(0,0,0,0,0,0,0,AD13,0,0,0,0,0,0)';
      BIDIRECTIONAL='TRUE';
      INPUT_LOAD='(-0.01,0.01)';
      OUTPUT_LOAD='(1.0,-1.0)';
    'GPP_L14_TESTCH1_D3':
      PIN_NUMBER='(0,0,0,0,0,0,0,AA13,0,0,0,0,0,0)';
      BIDIRECTIONAL='TRUE';
      INPUT_LOAD='(-0.01,0.01)';
      OUTPUT_LOAD='(1.0,-1.0)';
    'GPP_L15_TESTCH1_D4':
      PIN_NUMBER='(0,0,0,0,0,0,0,Y11,0,0,0,0,0,0)';
      BIDIRECTIONAL='TRUE';
      INPUT_LOAD='(-0.01,0.01)';
      OUTPUT_LOAD='(1.0,-1.0)';
    'GPP_L16_TESTCH1_D5':
      PIN_NUMBER='(0,0,0,0,0,0,0,Y7,0,0,0,0,0,0)';
      BIDIRECTIONAL='TRUE';
      INPUT_LOAD='(-0.01,0.01)';
      OUTPUT_LOAD='(1.0,-1.0)';
    'GPP_L17_TESTCH1_D6':
      PIN_NUMBER='(0,0,0,0,0,0,0,AA9,0,0,0,0,0,0)';
      BIDIRECTIONAL='TRUE';
      INPUT_LOAD='(-0.01,0.01)';
      OUTPUT_LOAD='(1.0,-1.0)';
    'GPP_L18_TESTCH1_D7':
      PIN_NUMBER='(0,0,0,0,0,0,0,AE7,0,0,0,0,0,0)';
      BIDIRECTIONAL='TRUE';
      INPUT_LOAD='(-0.01,0.01)';
      OUTPUT_LOAD='(1.0,-1.0)';
    'GPP_L19_TESTCH1_CLK':
      PIN_NUMBER='(0,0,0,0,0,0,0,AG11,0,0,0,0,0,0)';
      BIDIRECTIONAL='TRUE';
      INPUT_LOAD='(-0.01,0.01)';
      OUTPUT_LOAD='(1.0,-1.0)';
    'GPP_L2_TESTCH0_D0':
      PIN_NUMBER='(0,0,0,0,0,0,0,AE18,0,0,0,0,0,0)';
      BIDIRECTIONAL='TRUE';
      INPUT_LOAD='(-0.01,0.01)';
      OUTPUT_LOAD='(1.0,-1.0)';
    'GPP_L3_TESTCH0_D1':
      PIN_NUMBER='(0,0,0,0,0,0,0,AE15,0,0,0,0,0,0)';
      BIDIRECTIONAL='TRUE';
      INPUT_LOAD='(-0.01,0.01)';
      OUTPUT_LOAD='(1.0,-1.0)';
    'GPP_L4_TESTCH0_D2':
      PIN_NUMBER='(0,0,0,0,0,0,0,AE11,0,0,0,0,0,0)';
      BIDIRECTIONAL='TRUE';
      INPUT_LOAD='(-0.01,0.01)';
      OUTPUT_LOAD='(1.0,-1.0)';
    'GPP_L5_TESTCH0_D3':
      PIN_NUMBER='(0,0,0,0,0,0,0,Y18,0,0,0,0,0,0)';
      BIDIRECTIONAL='TRUE';
      INPUT_LOAD='(-0.01,0.01)';
      OUTPUT_LOAD='(1.0,-1.0)';
    'GPP_L6_TESTCH0_D4':
      PIN_NUMBER='(0,0,0,0,0,0,0,AA20,0,0,0,0,0,0)';
      BIDIRECTIONAL='TRUE';
      INPUT_LOAD='(-0.01,0.01)';
      OUTPUT_LOAD='(1.0,-1.0)';
    'GPP_L7_TESTCH0_D5':
      PIN_NUMBER='(0,0,0,0,0,0,0,AA17,0,0,0,0,0,0)';
      BIDIRECTIONAL='TRUE';
      INPUT_LOAD='(-0.01,0.01)';
      OUTPUT_LOAD='(1.0,-1.0)';
    'GPP_L8_TESTCH0_D6':
      PIN_NUMBER='(0,0,0,0,0,0,0,AD9,0,0,0,0,0,0)';
      BIDIRECTIONAL='TRUE';
      INPUT_LOAD='(-0.01,0.01)';
      OUTPUT_LOAD='(1.0,-1.0)';
    'GPP_L9_TESTCH0_D7':
      PIN_NUMBER='(0,0,0,0,0,0,0,AD17,0,0,0,0,0,0)';
      BIDIRECTIONAL='TRUE';
      INPUT_LOAD='(-0.01,0.01)';
      OUTPUT_LOAD='(1.0,-1.0)';
    'HDA_BCLK':
      PIN_NUMBER='(0,0,0,0,0,0,0,P18,0,0,0,0,0,0)';
      BIDIRECTIONAL='TRUE';
      INPUT_LOAD='(-0.01,0.01)';
      OUTPUT_LOAD='(1.0,-1.0)';
    'HDA_RST_N':
      PIN_NUMBER='(0,0,0,0,0,0,0,M18,0,0,0,0,0,0)';
      BIDIRECTIONAL='TRUE';
      INPUT_LOAD='(-0.01,0.01)';
      OUTPUT_LOAD='(1.0,-1.0)';
    'HDA_SDI_0':
      PIN_NUMBER='(0,0,0,0,0,0,0,K20,0,0,0,0,0,0)';
      BIDIRECTIONAL='TRUE';
      INPUT_LOAD='(-0.01,0.01)';
      OUTPUT_LOAD='(1.0,-1.0)';
    'HDA_SDI_1':
      PIN_NUMBER='(0,0,0,0,0,0,0,V18,0,0,0,0,0,0)';
      BIDIRECTIONAL='TRUE';
      INPUT_LOAD='(-0.01,0.01)';
      OUTPUT_LOAD='(1.0,-1.0)';
    'HDA_SDO':
      PIN_NUMBER='(0,0,0,0,0,0,0,U24,0,0,0,0,0,0)';
      BIDIRECTIONAL='TRUE';
      INPUT_LOAD='(-0.01,0.01)';
      OUTPUT_LOAD='(1.0,-1.0)';
    'HDA_SYNC':
      PIN_NUMBER='(0,0,0,0,0,0,0,H20,0,0,0,0,0,0)';
      BIDIRECTIONAL='TRUE';
      INPUT_LOAD='(-0.01,0.01)';
      OUTPUT_LOAD='(1.0,-1.0)';
    'INTRUDER_N':
      PIN_NUMBER='(0,0,0,0,0,0,0,AG18,0,0,0,0,0,0)';
      BIDIRECTIONAL='TRUE';
      INPUT_LOAD='(-0.01,0.01)';
      OUTPUT_LOAD='(1.0,-1.0)';
    'ITP_PMODE':
      PIN_NUMBER='(0,0,0,0,AR54,0,0,0,0,0,0,0,0,0)';
      BIDIRECTIONAL='TRUE';
      INPUT_LOAD='(-0.01,0.01)';
      OUTPUT_LOAD='(1.0,-1.0)';
    'JTAGX':
      PIN_NUMBER='(0,0,0,0,AF54,0,0,0,0,0,0,0,0,0)';
      BIDIRECTIONAL='TRUE';
      INPUT_LOAD='(-0.01,0.01)';
      OUTPUT_LOAD='(1.0,-1.0)';
    'JTAG_TCK':
      PIN_NUMBER='(0,0,0,0,AL56,0,0,0,0,0,0,0,0,0)';
      BIDIRECTIONAL='TRUE';
      INPUT_LOAD='(-0.01,0.01)';
      OUTPUT_LOAD='(1.0,-1.0)';
    'JTAG_TDI':
      PIN_NUMBER='(0,0,0,0,AN54,0,0,0,0,0,0,0,0,0)';
      BIDIRECTIONAL='TRUE';
      INPUT_LOAD='(-0.01,0.01)';
      OUTPUT_LOAD='(1.0,-1.0)';
    'JTAG_TDO':
      PIN_NUMBER='(0,0,0,0,AP56,0,0,0,0,0,0,0,0,0)';
      BIDIRECTIONAL='TRUE';
      INPUT_LOAD='(-0.01,0.01)';
      OUTPUT_LOAD='(1.0,-1.0)';
    'JTAG_TMS':
      PIN_NUMBER='(0,0,0,0,AH54,0,0,0,0,0,0,0,0,0)';
      BIDIRECTIONAL='TRUE';
      INPUT_LOAD='(-0.01,0.01)';
      OUTPUT_LOAD='(1.0,-1.0)';
    'LAN_RBIAS_0':
      PIN_NUMBER='(0,0,0,0,BB29,0,0,0,0,0,0,0,0,0)';
      BIDIRECTIONAL='TRUE';
      INPUT_LOAD='(-0.01,0.01)';
      OUTPUT_LOAD='(1.0,-1.0)';
    'LAN_RBIAS_1':
      PIN_NUMBER='(0,0,0,0,BD42,0,0,0,0,0,0,0,0,0)';
      BIDIRECTIONAL='TRUE';
      INPUT_LOAD='(-0.01,0.01)';
      OUTPUT_LOAD='(1.0,-1.0)';
    'LAN_RX_P0N':
      PIN_NUMBER='(0,0,0,0,BH31,0,0,0,0,0,0,0,0,0)';
      BIDIRECTIONAL='TRUE';
      INPUT_LOAD='(-0.01,0.01)';
      OUTPUT_LOAD='(1.0,-1.0)';
    'LAN_RX_P0P':
      PIN_NUMBER='(0,0,0,0,BF31,0,0,0,0,0,0,0,0,0)';
      BIDIRECTIONAL='TRUE';
      INPUT_LOAD='(-0.01,0.01)';
      OUTPUT_LOAD='(1.0,-1.0)';
    'LAN_RX_P1N':
      PIN_NUMBER='(0,0,0,0,BG29,0,0,0,0,0,0,0,0,0)';
      BIDIRECTIONAL='TRUE';
      INPUT_LOAD='(-0.01,0.01)';
      OUTPUT_LOAD='(1.0,-1.0)';
    'LAN_RX_P1P':
      PIN_NUMBER='(0,0,0,0,BJ29,0,0,0,0,0,0,0,0,0)';
      BIDIRECTIONAL='TRUE';
      INPUT_LOAD='(-0.01,0.01)';
      OUTPUT_LOAD='(1.0,-1.0)';
    'LAN_RX_P2N':
      PIN_NUMBER='(0,0,0,0,BJ37,0,0,0,0,0,0,0,0,0)';
      BIDIRECTIONAL='TRUE';
      INPUT_LOAD='(-0.01,0.01)';
      OUTPUT_LOAD='(1.0,-1.0)';
    'LAN_RX_P2P':
      PIN_NUMBER='(0,0,0,0,BG37,0,0,0,0,0,0,0,0,0)';
      BIDIRECTIONAL='TRUE';
      INPUT_LOAD='(-0.01,0.01)';
      OUTPUT_LOAD='(1.0,-1.0)';
    'LAN_RX_P3N':
      PIN_NUMBER='(0,0,0,0,BF35,0,0,0,0,0,0,0,0,0)';
      BIDIRECTIONAL='TRUE';
      INPUT_LOAD='(-0.01,0.01)';
      OUTPUT_LOAD='(1.0,-1.0)';
    'LAN_RX_P3P':
      PIN_NUMBER='(0,0,0,0,BH35,0,0,0,0,0,0,0,0,0)';
      BIDIRECTIONAL='TRUE';
      INPUT_LOAD='(-0.01,0.01)';
      OUTPUT_LOAD='(1.0,-1.0)';
    'LAN_TX_P0N':
      PIN_NUMBER='(0,0,0,0,BM27,0,0,0,0,0,0,0,0,0)';
      BIDIRECTIONAL='TRUE';
      INPUT_LOAD='(-0.01,0.01)';
      OUTPUT_LOAD='(1.0,-1.0)';
    'LAN_TX_P0P':
      PIN_NUMBER='(0,0,0,0,BR27,0,0,0,0,0,0,0,0,0)';
      BIDIRECTIONAL='TRUE';
      INPUT_LOAD='(-0.01,0.01)';
      OUTPUT_LOAD='(1.0,-1.0)';
    'LAN_TX_P1N':
      PIN_NUMBER='(0,0,0,0,BM24,0,0,0,0,0,0,0,0,0)';
      BIDIRECTIONAL='TRUE';
      INPUT_LOAD='(-0.01,0.01)';
      OUTPUT_LOAD='(1.0,-1.0)';
    'LAN_TX_P1P':
      PIN_NUMBER='(0,0,0,0,BR24,0,0,0,0,0,0,0,0,0)';
      BIDIRECTIONAL='TRUE';
      INPUT_LOAD='(-0.01,0.01)';
      OUTPUT_LOAD='(1.0,-1.0)';
    'LAN_TX_P2N':
      PIN_NUMBER='(0,0,0,0,BM35,0,0,0,0,0,0,0,0,0)';
      BIDIRECTIONAL='TRUE';
      INPUT_LOAD='(-0.01,0.01)';
      OUTPUT_LOAD='(1.0,-1.0)';
    'LAN_TX_P2P':
      PIN_NUMBER='(0,0,0,0,BR35,0,0,0,0,0,0,0,0,0)';
      BIDIRECTIONAL='TRUE';
      INPUT_LOAD='(-0.01,0.01)';
      OUTPUT_LOAD='(1.0,-1.0)';
    'LAN_TX_P3N':
      PIN_NUMBER='(0,0,0,0,BR31,0,0,0,0,0,0,0,0,0)';
      BIDIRECTIONAL='TRUE';
      INPUT_LOAD='(-0.01,0.01)';
      OUTPUT_LOAD='(1.0,-1.0)';
    'LAN_TX_P3P':
      PIN_NUMBER='(0,0,0,0,BM31,0,0,0,0,0,0,0,0,0)';
      BIDIRECTIONAL='TRUE';
      INPUT_LOAD='(-0.01,0.01)';
      OUTPUT_LOAD='(1.0,-1.0)';
    'LAN_XTAL_IN':
      PIN_NUMBER='(0,0,0,0,BV16,0,0,0,0,0,0,0,0,0)';
      BIDIRECTIONAL='TRUE';
      INPUT_LOAD='(-0.01,0.01)';
      OUTPUT_LOAD='(1.0,-1.0)';
    'LAN_XTAL_OUT':
      PIN_NUMBER='(0,0,0,0,BY16,0,0,0,0,0,0,0,0,0)';
      BIDIRECTIONAL='TRUE';
      INPUT_LOAD='(-0.01,0.01)';
      OUTPUT_LOAD='(1.0,-1.0)';
    'PCH_PWROK':
      PIN_NUMBER='(0,0,0,0,R17,0,0,0,0,0,0,0,0,0)';
      BIDIRECTIONAL='TRUE';
      INPUT_LOAD='(-0.01,0.01)';
      OUTPUT_LOAD='(1.0,-1.0)';
    'PCIE10_SSATA4_RXN':
      PIN_NUMBER='(0,0,AV63,0,0,0,0,0,0,0,0,0,0,0)';
      BIDIRECTIONAL='TRUE';
      INPUT_LOAD='(-0.01,0.01)';
      OUTPUT_LOAD='(1.0,-1.0)';
    'PCIE10_SSATA4_RXP':
      PIN_NUMBER='(0,0,AU65,0,0,0,0,0,0,0,0,0,0,0)';
      BIDIRECTIONAL='TRUE';
      INPUT_LOAD='(-0.01,0.01)';
      OUTPUT_LOAD='(1.0,-1.0)';
    'PCIE10_SSATA4_TXN':
      PIN_NUMBER='(0,0,AD70,0,0,0,0,0,0,0,0,0,0,0)';
      BIDIRECTIONAL='TRUE';
      INPUT_LOAD='(-0.01,0.01)';
      OUTPUT_LOAD='(1.0,-1.0)';
    'PCIE10_SSATA4_TXP':
      PIN_NUMBER='(0,0,AD72,0,0,0,0,0,0,0,0,0,0,0)';
      BIDIRECTIONAL='TRUE';
      INPUT_LOAD='(-0.01,0.01)';
      OUTPUT_LOAD='(1.0,-1.0)';
    'PCIE11_SSATA5_GBE_RXN':
      PIN_NUMBER='(0,0,AT66,0,0,0,0,0,0,0,0,0,0,0)';
      BIDIRECTIONAL='TRUE';
      INPUT_LOAD='(-0.01,0.01)';
      OUTPUT_LOAD='(1.0,-1.0)';
    'PCIE11_SSATA5_GBE_RXP':
      PIN_NUMBER='(0,0,AV66,0,0,0,0,0,0,0,0,0,0,0)';
      BIDIRECTIONAL='TRUE';
      INPUT_LOAD='(-0.01,0.01)';
      OUTPUT_LOAD='(1.0,-1.0)';
    'PCIE11_SSATA5_GBE_TXN':
      PIN_NUMBER='(0,0,AC69,0,0,0,0,0,0,0,0,0,0,0)';
      BIDIRECTIONAL='TRUE';
      INPUT_LOAD='(-0.01,0.01)';
      OUTPUT_LOAD='(1.0,-1.0)';
    'PCIE11_SSATA5_GBE_TXP':
      PIN_NUMBER='(0,0,AC71,0,0,0,0,0,0,0,0,0,0,0)';
      BIDIRECTIONAL='TRUE';
      INPUT_LOAD='(-0.01,0.01)';
      OUTPUT_LOAD='(1.0,-1.0)';
    'PCIE12_UP0_SATA0_RXN':
      PIN_NUMBER='(0,0,AR61,0,0,0,0,0,0,0,0,0,0,0)';
      BIDIRECTIONAL='TRUE';
      INPUT_LOAD='(-0.01,0.01)';
      OUTPUT_LOAD='(1.0,-1.0)';
    'PCIE12_UP0_SATA0_RXP':
      PIN_NUMBER='(0,0,AT63,0,0,0,0,0,0,0,0,0,0,0)';
      BIDIRECTIONAL='TRUE';
      INPUT_LOAD='(-0.01,0.01)';
      OUTPUT_LOAD='(1.0,-1.0)';
    'PCIE12_UP0_SATA0_TXN':
      PIN_NUMBER='(0,0,W69,0,0,0,0,0,0,0,0,0,0,0)';
      BIDIRECTIONAL='TRUE';
      INPUT_LOAD='(-0.01,0.01)';
      OUTPUT_LOAD='(1.0,-1.0)';
    'PCIE12_UP0_SATA0_TXP':
      PIN_NUMBER='(0,0,W71,0,0,0,0,0,0,0,0,0,0,0)';
      BIDIRECTIONAL='TRUE';
      INPUT_LOAD='(-0.01,0.01)';
      OUTPUT_LOAD='(1.0,-1.0)';
    'PCIE13_UP1_SATA1_RXN':
      PIN_NUMBER='(0,0,AL66,0,0,0,0,0,0,0,0,0,0,0)';
      BIDIRECTIONAL='TRUE';
      INPUT_LOAD='(-0.01,0.01)';
      OUTPUT_LOAD='(1.0,-1.0)';
    'PCIE13_UP1_SATA1_RXP':
      PIN_NUMBER='(0,0,AN65,0,0,0,0,0,0,0,0,0,0,0)';
      BIDIRECTIONAL='TRUE';
      INPUT_LOAD='(-0.01,0.01)';
      OUTPUT_LOAD='(1.0,-1.0)';
    'PCIE13_UP1_SATA1_TXN':
      PIN_NUMBER='(0,0,V70,0,0,0,0,0,0,0,0,0,0,0)';
      BIDIRECTIONAL='TRUE';
      INPUT_LOAD='(-0.01,0.01)';
      OUTPUT_LOAD='(1.0,-1.0)';
    'PCIE13_UP1_SATA1_TXP':
      PIN_NUMBER='(0,0,V72,0,0,0,0,0,0,0,0,0,0,0)';
      BIDIRECTIONAL='TRUE';
      INPUT_LOAD='(-0.01,0.01)';
      OUTPUT_LOAD='(1.0,-1.0)';
    'PCIE14_UP2_SATA2_RXN':
      PIN_NUMBER='(0,0,AK65,0,0,0,0,0,0,0,0,0,0,0)';
      BIDIRECTIONAL='TRUE';
      INPUT_LOAD='(-0.01,0.01)';
      OUTPUT_LOAD='(1.0,-1.0)';
    'PCIE14_UP2_SATA2_RXP':
      PIN_NUMBER='(0,0,AJ63,0,0,0,0,0,0,0,0,0,0,0)';
      BIDIRECTIONAL='TRUE';
      INPUT_LOAD='(-0.01,0.01)';
      OUTPUT_LOAD='(1.0,-1.0)';
    'PCIE14_UP2_SATA2_TXN':
      PIN_NUMBER='(0,0,T69,0,0,0,0,0,0,0,0,0,0,0)';
      BIDIRECTIONAL='TRUE';
      INPUT_LOAD='(-0.01,0.01)';
      OUTPUT_LOAD='(1.0,-1.0)';
    'PCIE14_UP2_SATA2_TXP':
      PIN_NUMBER='(0,0,T71,0,0,0,0,0,0,0,0,0,0,0)';
      BIDIRECTIONAL='TRUE';
      INPUT_LOAD='(-0.01,0.01)';
      OUTPUT_LOAD='(1.0,-1.0)';
    'PCIE15_UP3_SATA3_RXN':
      PIN_NUMBER='(0,0,AP63,0,0,0,0,0,0,0,0,0,0,0)';
      BIDIRECTIONAL='TRUE';
      INPUT_LOAD='(-0.01,0.01)';
      OUTPUT_LOAD='(1.0,-1.0)';
    'PCIE15_UP3_SATA3_RXP':
      PIN_NUMBER='(0,0,AL63,0,0,0,0,0,0,0,0,0,0,0)';
      BIDIRECTIONAL='TRUE';
      INPUT_LOAD='(-0.01,0.01)';
      OUTPUT_LOAD='(1.0,-1.0)';
    'PCIE15_UP3_SATA3_TXN':
      PIN_NUMBER='(0,0,R70,0,0,0,0,0,0,0,0,0,0,0)';
      BIDIRECTIONAL='TRUE';
      INPUT_LOAD='(-0.01,0.01)';
      OUTPUT_LOAD='(1.0,-1.0)';
    'PCIE15_UP3_SATA3_TXP':
      PIN_NUMBER='(0,0,R72,0,0,0,0,0,0,0,0,0,0,0)';
      BIDIRECTIONAL='TRUE';
      INPUT_LOAD='(-0.01,0.01)';
      OUTPUT_LOAD='(1.0,-1.0)';
    'PCIE16_UP4_SATA4_RXN':
      PIN_NUMBER='(0,0,AF65,0,0,0,0,0,0,0,0,0,0,0)';
      BIDIRECTIONAL='TRUE';
      INPUT_LOAD='(-0.01,0.01)';
      OUTPUT_LOAD='(1.0,-1.0)';
    'PCIE16_UP4_SATA4_RXP':
      PIN_NUMBER='(0,0,AH65,0,0,0,0,0,0,0,0,0,0,0)';
      BIDIRECTIONAL='TRUE';
      INPUT_LOAD='(-0.01,0.01)';
      OUTPUT_LOAD='(1.0,-1.0)';
    'PCIE16_UP4_SATA4_TXN':
      PIN_NUMBER='(0,0,P69,0,0,0,0,0,0,0,0,0,0,0)';
      BIDIRECTIONAL='TRUE';
      INPUT_LOAD='(-0.01,0.01)';
      OUTPUT_LOAD='(1.0,-1.0)';
    'PCIE16_UP4_SATA4_TXP':
      PIN_NUMBER='(0,0,P71,0,0,0,0,0,0,0,0,0,0,0)';
      BIDIRECTIONAL='TRUE';
      INPUT_LOAD='(-0.01,0.01)';
      OUTPUT_LOAD='(1.0,-1.0)';
    'PCIE17_UP5_SATA5_RXN':
      PIN_NUMBER='(0,0,AH61,0,0,0,0,0,0,0,0,0,0,0)';
      BIDIRECTIONAL='TRUE';
      INPUT_LOAD='(-0.01,0.01)';
      OUTPUT_LOAD='(1.0,-1.0)';
    'PCIE17_UP5_SATA5_RXP':
      PIN_NUMBER='(0,0,AG63,0,0,0,0,0,0,0,0,0,0,0)';
      BIDIRECTIONAL='TRUE';
      INPUT_LOAD='(-0.01,0.01)';
      OUTPUT_LOAD='(1.0,-1.0)';
    'PCIE17_UP5_SATA5_TXN':
      PIN_NUMBER='(0,0,N70,0,0,0,0,0,0,0,0,0,0,0)';
      BIDIRECTIONAL='TRUE';
      INPUT_LOAD='(-0.01,0.01)';
      OUTPUT_LOAD='(1.0,-1.0)';
    'PCIE17_UP5_SATA5_TXP':
      PIN_NUMBER='(0,0,N72,0,0,0,0,0,0,0,0,0,0,0)';
      BIDIRECTIONAL='TRUE';
      INPUT_LOAD='(-0.01,0.01)';
      OUTPUT_LOAD='(1.0,-1.0)';
    'PCIE18_UP6_SATA6_RXN':
      PIN_NUMBER='(0,0,AP59,0,0,0,0,0,0,0,0,0,0,0)';
      BIDIRECTIONAL='TRUE';
      INPUT_LOAD='(-0.01,0.01)';
      OUTPUT_LOAD='(1.0,-1.0)';
    'PCIE18_UP6_SATA6_RXP':
      PIN_NUMBER='(0,0,AN61,0,0,0,0,0,0,0,0,0,0,0)';
      BIDIRECTIONAL='TRUE';
      INPUT_LOAD='(-0.01,0.01)';
      OUTPUT_LOAD='(1.0,-1.0)';
    'PCIE18_UP6_SATA6_TXN':
      PIN_NUMBER='(0,0,M69,0,0,0,0,0,0,0,0,0,0,0)';
      BIDIRECTIONAL='TRUE';
      INPUT_LOAD='(-0.01,0.01)';
      OUTPUT_LOAD='(1.0,-1.0)';
    'PCIE18_UP6_SATA6_TXP':
      PIN_NUMBER='(0,0,M71,0,0,0,0,0,0,0,0,0,0,0)';
      BIDIRECTIONAL='TRUE';
      INPUT_LOAD='(-0.01,0.01)';
      OUTPUT_LOAD='(1.0,-1.0)';
    'PCIE19_UP7_SATA7_RXN':
      PIN_NUMBER='(0,0,AA61,0,0,0,0,0,0,0,0,0,0,0)';
      BIDIRECTIONAL='TRUE';
      INPUT_LOAD='(-0.01,0.01)';
      OUTPUT_LOAD='(1.0,-1.0)';
    'PCIE19_UP7_SATA7_RXP':
      PIN_NUMBER='(0,0,AD61,0,0,0,0,0,0,0,0,0,0,0)';
      BIDIRECTIONAL='TRUE';
      INPUT_LOAD='(-0.01,0.01)';
      OUTPUT_LOAD='(1.0,-1.0)';
    'PCIE19_UP7_SATA7_TXN':
      PIN_NUMBER='(0,0,L70,0,0,0,0,0,0,0,0,0,0,0)';
      BIDIRECTIONAL='TRUE';
      INPUT_LOAD='(-0.01,0.01)';
      OUTPUT_LOAD='(1.0,-1.0)';
    'PCIE19_UP7_SATA7_TXP':
      PIN_NUMBER='(0,0,L72,0,0,0,0,0,0,0,0,0,0,0)';
      BIDIRECTIONAL='TRUE';
      INPUT_LOAD='(-0.01,0.01)';
      OUTPUT_LOAD='(1.0,-1.0)';
    'PCIE4_GBE_RXN':
      PIN_NUMBER='(0,0,AN70,0,0,0,0,0,0,0,0,0,0,0)';
      BIDIRECTIONAL='TRUE';
      INPUT_LOAD='(-0.01,0.01)';
      OUTPUT_LOAD='(1.0,-1.0)';
    'PCIE4_GBE_RXP':
      PIN_NUMBER='(0,0,AN72,0,0,0,0,0,0,0,0,0,0,0)';
      BIDIRECTIONAL='TRUE';
      INPUT_LOAD='(-0.01,0.01)';
      OUTPUT_LOAD='(1.0,-1.0)';
    'PCIE4_GBE_TXN':
      PIN_NUMBER='(0,0,BG66,0,0,0,0,0,0,0,0,0,0,0)';
      BIDIRECTIONAL='TRUE';
      INPUT_LOAD='(-0.01,0.01)';
      OUTPUT_LOAD='(1.0,-1.0)';
    'PCIE4_GBE_TXP':
      PIN_NUMBER='(0,0,BJ66,0,0,0,0,0,0,0,0,0,0,0)';
      BIDIRECTIONAL='TRUE';
      INPUT_LOAD='(-0.01,0.01)';
      OUTPUT_LOAD='(1.0,-1.0)';
    'PCIE5_GBE_RXN':
      PIN_NUMBER='(0,0,AM69,0,0,0,0,0,0,0,0,0,0,0)';
      BIDIRECTIONAL='TRUE';
      INPUT_LOAD='(-0.01,0.01)';
      OUTPUT_LOAD='(1.0,-1.0)';
    'PCIE5_GBE_RXP':
      PIN_NUMBER='(0,0,AM71,0,0,0,0,0,0,0,0,0,0,0)';
      BIDIRECTIONAL='TRUE';
      INPUT_LOAD='(-0.01,0.01)';
      OUTPUT_LOAD='(1.0,-1.0)';
    'PCIE5_GBE_TXN':
      PIN_NUMBER='(0,0,BH65,0,0,0,0,0,0,0,0,0,0,0)';
      BIDIRECTIONAL='TRUE';
      INPUT_LOAD='(-0.01,0.01)';
      OUTPUT_LOAD='(1.0,-1.0)';
    'PCIE5_GBE_TXP':
      PIN_NUMBER='(0,0,BJ63,0,0,0,0,0,0,0,0,0,0,0)';
      BIDIRECTIONAL='TRUE';
      INPUT_LOAD='(-0.01,0.01)';
      OUTPUT_LOAD='(1.0,-1.0)';
    'PCIE6_SSATA0_RXN':
      PIN_NUMBER='(0,0,BB63,0,0,0,0,0,0,0,0,0,0,0)';
      BIDIRECTIONAL='TRUE';
      INPUT_LOAD='(-0.01,0.01)';
      OUTPUT_LOAD='(1.0,-1.0)';
    'PCIE6_SSATA0_RXP':
      PIN_NUMBER='(0,0,BD61,0,0,0,0,0,0,0,0,0,0,0)';
      BIDIRECTIONAL='TRUE';
      INPUT_LOAD='(-0.01,0.01)';
      OUTPUT_LOAD='(1.0,-1.0)';
    'PCIE6_SSATA0_TXN':
      PIN_NUMBER='(0,0,AJ70,0,0,0,0,0,0,0,0,0,0,0)';
      BIDIRECTIONAL='TRUE';
      INPUT_LOAD='(-0.01,0.01)';
      OUTPUT_LOAD='(1.0,-1.0)';
    'PCIE6_SSATA0_TXP':
      PIN_NUMBER='(0,0,AJ72,0,0,0,0,0,0,0,0,0,0,0)';
      BIDIRECTIONAL='TRUE';
      INPUT_LOAD='(-0.01,0.01)';
      OUTPUT_LOAD='(1.0,-1.0)';
    'PCIE7_SSATA1_RXN':
      PIN_NUMBER='(0,0,AY59,0,0,0,0,0,0,0,0,0,0,0)';
      BIDIRECTIONAL='TRUE';
      INPUT_LOAD='(-0.01,0.01)';
      OUTPUT_LOAD='(1.0,-1.0)';
    'PCIE7_SSATA1_RXP':
      PIN_NUMBER='(0,0,BA61,0,0,0,0,0,0,0,0,0,0,0)';
      BIDIRECTIONAL='TRUE';
      INPUT_LOAD='(-0.01,0.01)';
      OUTPUT_LOAD='(1.0,-1.0)';
    'PCIE7_SSATA1_TXN':
      PIN_NUMBER='(0,0,AH69,0,0,0,0,0,0,0,0,0,0,0)';
      BIDIRECTIONAL='TRUE';
      INPUT_LOAD='(-0.01,0.01)';
      OUTPUT_LOAD='(1.0,-1.0)';
    'PCIE7_SSATA1_TXP':
      PIN_NUMBER='(0,0,AH71,0,0,0,0,0,0,0,0,0,0,0)';
      BIDIRECTIONAL='TRUE';
      INPUT_LOAD='(-0.01,0.01)';
      OUTPUT_LOAD='(1.0,-1.0)';
    'PCIE8_SSATA2_GBE_RXN':
      PIN_NUMBER='(0,0,BA65,0,0,0,0,0,0,0,0,0,0,0)';
      BIDIRECTIONAL='TRUE';
      INPUT_LOAD='(-0.01,0.01)';
      OUTPUT_LOAD='(1.0,-1.0)';
    'PCIE8_SSATA2_GBE_RXP':
      PIN_NUMBER='(0,0,BD65,0,0,0,0,0,0,0,0,0,0,0)';
      BIDIRECTIONAL='TRUE';
      INPUT_LOAD='(-0.01,0.01)';
      OUTPUT_LOAD='(1.0,-1.0)';
    'PCIE8_SSATA2_GBE_TXN':
      PIN_NUMBER='(0,0,AF70,0,0,0,0,0,0,0,0,0,0,0)';
      BIDIRECTIONAL='TRUE';
      INPUT_LOAD='(-0.01,0.01)';
      OUTPUT_LOAD='(1.0,-1.0)';
    'PCIE8_SSATA2_GBE_TXP':
      PIN_NUMBER='(0,0,AF72,0,0,0,0,0,0,0,0,0,0,0)';
      BIDIRECTIONAL='TRUE';
      INPUT_LOAD='(-0.01,0.01)';
      OUTPUT_LOAD='(1.0,-1.0)';
    'PCIE9_SSATA3_RXN':
      PIN_NUMBER='(0,0,AW65,0,0,0,0,0,0,0,0,0,0,0)';
      BIDIRECTIONAL='TRUE';
      INPUT_LOAD='(-0.01,0.01)';
      OUTPUT_LOAD='(1.0,-1.0)';
    'PCIE9_SSATA3_RXP':
      PIN_NUMBER='(0,0,AY66,0,0,0,0,0,0,0,0,0,0,0)';
      BIDIRECTIONAL='TRUE';
      INPUT_LOAD='(-0.01,0.01)';
      OUTPUT_LOAD='(1.0,-1.0)';
    'PCIE9_SSATA3_TXN':
      PIN_NUMBER='(0,0,AE69,0,0,0,0,0,0,0,0,0,0,0)';
      BIDIRECTIONAL='TRUE';
      INPUT_LOAD='(-0.01,0.01)';
      OUTPUT_LOAD='(1.0,-1.0)';
    'PCIE9_SSATA3_TXP':
      PIN_NUMBER='(0,0,AE71,0,0,0,0,0,0,0,0,0,0,0)';
      BIDIRECTIONAL='TRUE';
      INPUT_LOAD='(-0.01,0.01)';
      OUTPUT_LOAD='(1.0,-1.0)';
    'PCIEUP_0_RXN':
      PIN_NUMBER='(0,0,0,C48,0,0,0,0,0,0,0,0,0,0)';
      BIDIRECTIONAL='TRUE';
      INPUT_LOAD='(-0.01,0.01)';
      OUTPUT_LOAD='(1.0,-1.0)';
    'PCIEUP_0_RXP':
      PIN_NUMBER='(0,0,0,A48,0,0,0,0,0,0,0,0,0,0)';
      BIDIRECTIONAL='TRUE';
      INPUT_LOAD='(-0.01,0.01)';
      OUTPUT_LOAD='(1.0,-1.0)';
    'PCIEUP_0_TXN':
      PIN_NUMBER='(0,0,0,J52,0,0,0,0,0,0,0,0,0,0)';
      BIDIRECTIONAL='TRUE';
      INPUT_LOAD='(-0.01,0.01)';
      OUTPUT_LOAD='(1.0,-1.0)';
    'PCIEUP_0_TXP':
      PIN_NUMBER='(0,0,0,G52,0,0,0,0,0,0,0,0,0,0)';
      BIDIRECTIONAL='TRUE';
      INPUT_LOAD='(-0.01,0.01)';
      OUTPUT_LOAD='(1.0,-1.0)';
    'PCIEUP_10_RXN':
      PIN_NUMBER='(0,0,0,C59,0,0,0,0,0,0,0,0,0,0)';
      BIDIRECTIONAL='TRUE';
      INPUT_LOAD='(-0.01,0.01)';
      OUTPUT_LOAD='(1.0,-1.0)';
    'PCIEUP_10_RXP':
      PIN_NUMBER='(0,0,0,A59,0,0,0,0,0,0,0,0,0,0)';
      BIDIRECTIONAL='TRUE';
      INPUT_LOAD='(-0.01,0.01)';
      OUTPUT_LOAD='(1.0,-1.0)';
    'PCIEUP_10_TXN':
      PIN_NUMBER='(0,0,0,N65,0,0,0,0,0,0,0,0,0,0)';
      BIDIRECTIONAL='TRUE';
      INPUT_LOAD='(-0.01,0.01)';
      OUTPUT_LOAD='(1.0,-1.0)';
    'PCIEUP_10_TXP':
      PIN_NUMBER='(0,0,0,P66,0,0,0,0,0,0,0,0,0,0)';
      BIDIRECTIONAL='TRUE';
      INPUT_LOAD='(-0.01,0.01)';
      OUTPUT_LOAD='(1.0,-1.0)';
    'PCIEUP_11_RXN':
      PIN_NUMBER='(0,0,0,D60,0,0,0,0,0,0,0,0,0,0)';
      BIDIRECTIONAL='TRUE';
      INPUT_LOAD='(-0.01,0.01)';
      OUTPUT_LOAD='(1.0,-1.0)';
    'PCIEUP_11_RXP':
      PIN_NUMBER='(0,0,0,B60,0,0,0,0,0,0,0,0,0,0)';
      BIDIRECTIONAL='TRUE';
      INPUT_LOAD='(-0.01,0.01)';
      OUTPUT_LOAD='(1.0,-1.0)';
    'PCIEUP_11_TXN':
      PIN_NUMBER='(0,0,0,T59,0,0,0,0,0,0,0,0,0,0)';
      BIDIRECTIONAL='TRUE';
      INPUT_LOAD='(-0.01,0.01)';
      OUTPUT_LOAD='(1.0,-1.0)';
    'PCIEUP_11_TXP':
      PIN_NUMBER='(0,0,0,V59,0,0,0,0,0,0,0,0,0,0)';
      BIDIRECTIONAL='TRUE';
      INPUT_LOAD='(-0.01,0.01)';
      OUTPUT_LOAD='(1.0,-1.0)';
    'PCIEUP_12_RXN':
      PIN_NUMBER='(0,0,0,C61,0,0,0,0,0,0,0,0,0,0)';
      BIDIRECTIONAL='TRUE';
      INPUT_LOAD='(-0.01,0.01)';
      OUTPUT_LOAD='(1.0,-1.0)';
    'PCIEUP_12_RXP':
      PIN_NUMBER='(0,0,0,A61,0,0,0,0,0,0,0,0,0,0)';
      BIDIRECTIONAL='TRUE';
      INPUT_LOAD='(-0.01,0.01)';
      OUTPUT_LOAD='(1.0,-1.0)';
    'PCIEUP_12_TXN':
      PIN_NUMBER='(0,0,0,R65,0,0,0,0,0,0,0,0,0,0)';
      BIDIRECTIONAL='TRUE';
      INPUT_LOAD='(-0.01,0.01)';
      OUTPUT_LOAD='(1.0,-1.0)';
    'PCIEUP_12_TXP':
      PIN_NUMBER='(0,0,0,U65,0,0,0,0,0,0,0,0,0,0)';
      BIDIRECTIONAL='TRUE';
      INPUT_LOAD='(-0.01,0.01)';
      OUTPUT_LOAD='(1.0,-1.0)';
    'PCIEUP_13_RXN':
      PIN_NUMBER='(0,0,0,D62,0,0,0,0,0,0,0,0,0,0)';
      BIDIRECTIONAL='TRUE';
      INPUT_LOAD='(-0.01,0.01)';
      OUTPUT_LOAD='(1.0,-1.0)';
    'PCIEUP_13_RXP':
      PIN_NUMBER='(0,0,0,B62,0,0,0,0,0,0,0,0,0,0)';
      BIDIRECTIONAL='TRUE';
      INPUT_LOAD='(-0.01,0.01)';
      OUTPUT_LOAD='(1.0,-1.0)';
    'PCIEUP_13_TXN':
      PIN_NUMBER='(0,0,0,T63,0,0,0,0,0,0,0,0,0,0)';
      BIDIRECTIONAL='TRUE';
      INPUT_LOAD='(-0.01,0.01)';
      OUTPUT_LOAD='(1.0,-1.0)';
    'PCIEUP_13_TXP':
      PIN_NUMBER='(0,0,0,U61,0,0,0,0,0,0,0,0,0,0)';
      BIDIRECTIONAL='TRUE';
      INPUT_LOAD='(-0.01,0.01)';
      OUTPUT_LOAD='(1.0,-1.0)';
    'PCIEUP_14_RXN':
      PIN_NUMBER='(0,0,0,C63,0,0,0,0,0,0,0,0,0,0)';
      BIDIRECTIONAL='TRUE';
      INPUT_LOAD='(-0.01,0.01)';
      OUTPUT_LOAD='(1.0,-1.0)';
    'PCIEUP_14_RXP':
      PIN_NUMBER='(0,0,0,A63,0,0,0,0,0,0,0,0,0,0)';
      BIDIRECTIONAL='TRUE';
      INPUT_LOAD='(-0.01,0.01)';
      OUTPUT_LOAD='(1.0,-1.0)';
    'PCIEUP_14_TXN':
      PIN_NUMBER='(0,0,0,W65,0,0,0,0,0,0,0,0,0,0)';
      BIDIRECTIONAL='TRUE';
      INPUT_LOAD='(-0.01,0.01)';
      OUTPUT_LOAD='(1.0,-1.0)';
    'PCIEUP_14_TXP':
      PIN_NUMBER='(0,0,0,V63,0,0,0,0,0,0,0,0,0,0)';
      BIDIRECTIONAL='TRUE';
      INPUT_LOAD='(-0.01,0.01)';
      OUTPUT_LOAD='(1.0,-1.0)';
    'PCIEUP_15_RXN':
      PIN_NUMBER='(0,0,0,D64,0,0,0,0,0,0,0,0,0,0)';
      BIDIRECTIONAL='TRUE';
      INPUT_LOAD='(-0.01,0.01)';
      OUTPUT_LOAD='(1.0,-1.0)';
    'PCIEUP_15_RXP':
      PIN_NUMBER='(0,0,0,B64,0,0,0,0,0,0,0,0,0,0)';
      BIDIRECTIONAL='TRUE';
      INPUT_LOAD='(-0.01,0.01)';
      OUTPUT_LOAD='(1.0,-1.0)';
    'PCIEUP_15_TXN':
      PIN_NUMBER='(0,0,0,Y66,0,0,0,0,0,0,0,0,0,0)';
      BIDIRECTIONAL='TRUE';
      INPUT_LOAD='(-0.01,0.01)';
      OUTPUT_LOAD='(1.0,-1.0)';
    'PCIEUP_15_TXP':
      PIN_NUMBER='(0,0,0,AA65,0,0,0,0,0,0,0,0,0,0)';
      BIDIRECTIONAL='TRUE';
      INPUT_LOAD='(-0.01,0.01)';
      OUTPUT_LOAD='(1.0,-1.0)';
    'PCIEUP_1_RXN':
      PIN_NUMBER='(0,0,0,D49,0,0,0,0,0,0,0,0,0,0)';
      BIDIRECTIONAL='TRUE';
      INPUT_LOAD='(-0.01,0.01)';
      OUTPUT_LOAD='(1.0,-1.0)';
    'PCIEUP_1_RXP':
      PIN_NUMBER='(0,0,0,B49,0,0,0,0,0,0,0,0,0,0)';
      BIDIRECTIONAL='TRUE';
      INPUT_LOAD='(-0.01,0.01)';
      OUTPUT_LOAD='(1.0,-1.0)';
    'PCIEUP_1_TXN':
      PIN_NUMBER='(0,0,0,P56,0,0,0,0,0,0,0,0,0,0)';
      BIDIRECTIONAL='TRUE';
      INPUT_LOAD='(-0.01,0.01)';
      OUTPUT_LOAD='(1.0,-1.0)';
    'PCIEUP_1_TXP':
      PIN_NUMBER='(0,0,0,M56,0,0,0,0,0,0,0,0,0,0)';
      BIDIRECTIONAL='TRUE';
      INPUT_LOAD='(-0.01,0.01)';
      OUTPUT_LOAD='(1.0,-1.0)';
    'PCIEUP_2_RXN':
      PIN_NUMBER='(0,0,0,C50,0,0,0,0,0,0,0,0,0,0)';
      BIDIRECTIONAL='TRUE';
      INPUT_LOAD='(-0.01,0.01)';
      OUTPUT_LOAD='(1.0,-1.0)';
    'PCIEUP_2_RXP':
      PIN_NUMBER='(0,0,0,A50,0,0,0,0,0,0,0,0,0,0)';
      BIDIRECTIONAL='TRUE';
      INPUT_LOAD='(-0.01,0.01)';
      OUTPUT_LOAD='(1.0,-1.0)';
    'PCIEUP_2_TXN':
      PIN_NUMBER='(0,0,0,H54,0,0,0,0,0,0,0,0,0,0)';
      BIDIRECTIONAL='TRUE';
      INPUT_LOAD='(-0.01,0.01)';
      OUTPUT_LOAD='(1.0,-1.0)';
    'PCIEUP_2_TXP':
      PIN_NUMBER='(0,0,0,G56,0,0,0,0,0,0,0,0,0,0)';
      BIDIRECTIONAL='TRUE';
      INPUT_LOAD='(-0.01,0.01)';
      OUTPUT_LOAD='(1.0,-1.0)';
    'PCIEUP_3_RXN':
      PIN_NUMBER='(0,0,0,D51,0,0,0,0,0,0,0,0,0,0)';
      BIDIRECTIONAL='TRUE';
      INPUT_LOAD='(-0.01,0.01)';
      OUTPUT_LOAD='(1.0,-1.0)';
    'PCIEUP_3_RXP':
      PIN_NUMBER='(0,0,0,B51,0,0,0,0,0,0,0,0,0,0)';
      BIDIRECTIONAL='TRUE';
      INPUT_LOAD='(-0.01,0.01)';
      OUTPUT_LOAD='(1.0,-1.0)';
    'PCIEUP_3_TXN':
      PIN_NUMBER='(0,0,0,J56,0,0,0,0,0,0,0,0,0,0)';
      BIDIRECTIONAL='TRUE';
      INPUT_LOAD='(-0.01,0.01)';
      OUTPUT_LOAD='(1.0,-1.0)';
    'PCIEUP_3_TXP':
      PIN_NUMBER='(0,0,0,K58,0,0,0,0,0,0,0,0,0,0)';
      BIDIRECTIONAL='TRUE';
      INPUT_LOAD='(-0.01,0.01)';
      OUTPUT_LOAD='(1.0,-1.0)';
    'PCIEUP_4_RXN':
      PIN_NUMBER='(0,0,0,C52,0,0,0,0,0,0,0,0,0,0)';
      BIDIRECTIONAL='TRUE';
      INPUT_LOAD='(-0.01,0.01)';
      OUTPUT_LOAD='(1.0,-1.0)';
    'PCIEUP_4_RXP':
      PIN_NUMBER='(0,0,0,A52,0,0,0,0,0,0,0,0,0,0)';
      BIDIRECTIONAL='TRUE';
      INPUT_LOAD='(-0.01,0.01)';
      OUTPUT_LOAD='(1.0,-1.0)';
    'PCIEUP_4_TXN':
      PIN_NUMBER='(0,0,0,N58,0,0,0,0,0,0,0,0,0,0)';
      BIDIRECTIONAL='TRUE';
      INPUT_LOAD='(-0.01,0.01)';
      OUTPUT_LOAD='(1.0,-1.0)';
    'PCIEUP_4_TXP':
      PIN_NUMBER='(0,0,0,M59,0,0,0,0,0,0,0,0,0,0)';
      BIDIRECTIONAL='TRUE';
      INPUT_LOAD='(-0.01,0.01)';
      OUTPUT_LOAD='(1.0,-1.0)';
    'PCIEUP_5_RXN':
      PIN_NUMBER='(0,0,0,D53,0,0,0,0,0,0,0,0,0,0)';
      BIDIRECTIONAL='TRUE';
      INPUT_LOAD='(-0.01,0.01)';
      OUTPUT_LOAD='(1.0,-1.0)';
    'PCIEUP_5_RXP':
      PIN_NUMBER='(0,0,0,B53,0,0,0,0,0,0,0,0,0,0)';
      BIDIRECTIONAL='TRUE';
      INPUT_LOAD='(-0.01,0.01)';
      OUTPUT_LOAD='(1.0,-1.0)';
    'PCIEUP_5_TXN':
      PIN_NUMBER='(0,0,0,N61,0,0,0,0,0,0,0,0,0,0)';
      BIDIRECTIONAL='TRUE';
      INPUT_LOAD='(-0.01,0.01)';
      OUTPUT_LOAD='(1.0,-1.0)';
    'PCIEUP_5_TXP':
      PIN_NUMBER='(0,0,0,K61,0,0,0,0,0,0,0,0,0,0)';
      BIDIRECTIONAL='TRUE';
      INPUT_LOAD='(-0.01,0.01)';
      OUTPUT_LOAD='(1.0,-1.0)';
    'PCIEUP_6_RXN':
      PIN_NUMBER='(0,0,0,C54,0,0,0,0,0,0,0,0,0,0)';
      BIDIRECTIONAL='TRUE';
      INPUT_LOAD='(-0.01,0.01)';
      OUTPUT_LOAD='(1.0,-1.0)';
    'PCIEUP_6_RXP':
      PIN_NUMBER='(0,0,0,A54,0,0,0,0,0,0,0,0,0,0)';
      BIDIRECTIONAL='TRUE';
      INPUT_LOAD='(-0.01,0.01)';
      OUTPUT_LOAD='(1.0,-1.0)';
    'PCIEUP_6_TXN':
      PIN_NUMBER='(0,0,0,H61,0,0,0,0,0,0,0,0,0,0)';
      BIDIRECTIONAL='TRUE';
      INPUT_LOAD='(-0.01,0.01)';
      OUTPUT_LOAD='(1.0,-1.0)';
    'PCIEUP_6_TXP':
      PIN_NUMBER='(0,0,0,J63,0,0,0,0,0,0,0,0,0,0)';
      BIDIRECTIONAL='TRUE';
      INPUT_LOAD='(-0.01,0.01)';
      OUTPUT_LOAD='(1.0,-1.0)';
    'PCIEUP_7_RXN':
      PIN_NUMBER='(0,0,0,D55,0,0,0,0,0,0,0,0,0,0)';
      BIDIRECTIONAL='TRUE';
      INPUT_LOAD='(-0.01,0.01)';
      OUTPUT_LOAD='(1.0,-1.0)';
    'PCIEUP_7_RXP':
      PIN_NUMBER='(0,0,0,B55,0,0,0,0,0,0,0,0,0,0)';
      BIDIRECTIONAL='TRUE';
      INPUT_LOAD='(-0.01,0.01)';
      OUTPUT_LOAD='(1.0,-1.0)';
    'PCIEUP_7_TXN':
      PIN_NUMBER='(0,0,0,P59,0,0,0,0,0,0,0,0,0,0)';
      BIDIRECTIONAL='TRUE';
      INPUT_LOAD='(-0.01,0.01)';
      OUTPUT_LOAD='(1.0,-1.0)';
    'PCIEUP_7_TXP':
      PIN_NUMBER='(0,0,0,R61,0,0,0,0,0,0,0,0,0,0)';
      BIDIRECTIONAL='TRUE';
      INPUT_LOAD='(-0.01,0.01)';
      OUTPUT_LOAD='(1.0,-1.0)';
    'PCIEUP_8_RXN':
      PIN_NUMBER='(0,0,0,C57,0,0,0,0,0,0,0,0,0,0)';
      BIDIRECTIONAL='TRUE';
      INPUT_LOAD='(-0.01,0.01)';
      OUTPUT_LOAD='(1.0,-1.0)';
    'PCIEUP_8_RXP':
      PIN_NUMBER='(0,0,0,A57,0,0,0,0,0,0,0,0,0,0)';
      BIDIRECTIONAL='TRUE';
      INPUT_LOAD='(-0.01,0.01)';
      OUTPUT_LOAD='(1.0,-1.0)';
    'PCIEUP_8_TXN':
      PIN_NUMBER='(0,0,0,K65,0,0,0,0,0,0,0,0,0,0)';
      BIDIRECTIONAL='TRUE';
      INPUT_LOAD='(-0.01,0.01)';
      OUTPUT_LOAD='(1.0,-1.0)';
    'PCIEUP_8_TXP':
      PIN_NUMBER='(0,0,0,M63,0,0,0,0,0,0,0,0,0,0)';
      BIDIRECTIONAL='TRUE';
      INPUT_LOAD='(-0.01,0.01)';
      OUTPUT_LOAD='(1.0,-1.0)';
    'PCIEUP_9_RXN':
      PIN_NUMBER='(0,0,0,D58,0,0,0,0,0,0,0,0,0,0)';
      BIDIRECTIONAL='TRUE';
      INPUT_LOAD='(-0.01,0.01)';
      OUTPUT_LOAD='(1.0,-1.0)';
    'PCIEUP_9_RXP':
      PIN_NUMBER='(0,0,0,B58,0,0,0,0,0,0,0,0,0,0)';
      BIDIRECTIONAL='TRUE';
      INPUT_LOAD='(-0.01,0.01)';
      OUTPUT_LOAD='(1.0,-1.0)';
    'PCIEUP_9_TXN':
      PIN_NUMBER='(0,0,0,J66,0,0,0,0,0,0,0,0,0,0)';
      BIDIRECTIONAL='TRUE';
      INPUT_LOAD='(-0.01,0.01)';
      OUTPUT_LOAD='(1.0,-1.0)';
    'PCIEUP_9_TXP':
      PIN_NUMBER='(0,0,0,M66,0,0,0,0,0,0,0,0,0,0)';
      BIDIRECTIONAL='TRUE';
      INPUT_LOAD='(-0.01,0.01)';
      OUTPUT_LOAD='(1.0,-1.0)';
    'PCIEUP_RCOMPN':
      PIN_NUMBER='(0,0,AF58,0,0,0,0,0,0,0,0,0,0,0)';
      BIDIRECTIONAL='TRUE';
      INPUT_LOAD='(-0.01,0.01)';
      OUTPUT_LOAD='(1.0,-1.0)';
    'PCIEUP_RCOMPP':
      PIN_NUMBER='(0,0,AH58,0,0,0,0,0,0,0,0,0,0,0)';
      BIDIRECTIONAL='TRUE';
      INPUT_LOAD='(-0.01,0.01)';
      OUTPUT_LOAD='(1.0,-1.0)';
    'PCIE_RCOMPN':
      PIN_NUMBER='(0,0,BD58,0,0,0,0,0,0,0,0,0,0,0)';
      BIDIRECTIONAL='TRUE';
      INPUT_LOAD='(-0.01,0.01)';
      OUTPUT_LOAD='(1.0,-1.0)';
    'PCIE_RCOMPP':
      PIN_NUMBER='(0,0,BB56,0,0,0,0,0,0,0,0,0,0,0)';
      BIDIRECTIONAL='TRUE';
      INPUT_LOAD='(-0.01,0.01)';
      OUTPUT_LOAD='(1.0,-1.0)';
    'PECI':
      PIN_NUMBER='(0,0,0,0,U9,0,0,0,0,0,0,0,0,0)';
      BIDIRECTIONAL='TRUE';
      INPUT_LOAD='(-0.01,0.01)';
      OUTPUT_LOAD='(1.0,-1.0)';
    'PLTRST_CPU_N':
      PIN_NUMBER='(0,0,0,0,U17,0,0,0,0,0,0,0,0,0)';
      BIDIRECTIONAL='TRUE';
      INPUT_LOAD='(-0.01,0.01)';
      OUTPUT_LOAD='(1.0,-1.0)';
    'PM_SYNC':
      PIN_NUMBER='(0,0,0,0,U13,0,0,0,0,0,0,0,0,0)';
      BIDIRECTIONAL='TRUE';
      INPUT_LOAD='(-0.01,0.01)';
      OUTPUT_LOAD='(1.0,-1.0)';
    'PM_SYNC2':
      PIN_NUMBER='(0,0,0,0,V7,0,0,0,0,0,0,0,0,0)';
      BIDIRECTIONAL='TRUE';
      INPUT_LOAD='(-0.01,0.01)';
      OUTPUT_LOAD='(1.0,-1.0)';
    'PRDY_N':
      PIN_NUMBER='(0,0,0,0,AD54,0,0,0,0,0,0,0,0,0)';
      BIDIRECTIONAL='TRUE';
      INPUT_LOAD='(-0.01,0.01)';
      OUTPUT_LOAD='(1.0,-1.0)';
    'PREQ_N':
      PIN_NUMBER='(0,0,0,0,U54,0,0,0,0,0,0,0,0,0)';
      BIDIRECTIONAL='TRUE';
      INPUT_LOAD='(-0.01,0.01)';
      OUTPUT_LOAD='(1.0,-1.0)';
    'PROC_PWRGD':
      PIN_NUMBER='(0,0,0,0,R9,0,0,0,0,0,0,0,0,0)';
      BIDIRECTIONAL='TRUE';
      INPUT_LOAD='(-0.01,0.01)';
      OUTPUT_LOAD='(1.0,-1.0)';
    'RSMRST_N':
      PIN_NUMBER='(0,0,0,0,P15,0,0,0,0,0,0,0,0,0)';
      BIDIRECTIONAL='TRUE';
      INPUT_LOAD='(-0.01,0.01)';
      OUTPUT_LOAD='(1.0,-1.0)';
    'RSVD'<68>:
      PIN_NUMBER='(0,0,0,0,0,0,0,V22,0,0,0,0,0,0)';
      BIDIRECTIONAL='TRUE';
      INPUT_LOAD='(-0.01,0.01)';
      OUTPUT_LOAD='(1.0,-1.0)';
    'RSVD'<67>:
      PIN_NUMBER='(0,0,0,0,0,0,0,R20,0,0,0,0,0,0)';
      BIDIRECTIONAL='TRUE';
      INPUT_LOAD='(-0.01,0.01)';
      OUTPUT_LOAD='(1.0,-1.0)';
    'RSVD'<66>:
      PIN_NUMBER='(0,0,0,0,0,0,0,U20,0,0,0,0,0,0)';
      BIDIRECTIONAL='TRUE';
      INPUT_LOAD='(-0.01,0.01)';
      OUTPUT_LOAD='(1.0,-1.0)';
    'RSVD'<65>:
      PIN_NUMBER='(A26,0,0,0,0,0,0,0,0,0,0,0,0,0)';
      PINUSE='UNSPEC';
      NO_LOAD_CHECK='Both';
      NO_IO_CHECK='Both';
      NO_ASSERT_CHECK='TRUE';
      NO_DIR_CHECK='TRUE';
      ALLOW_CONNECT='TRUE';
    'RSVD'<64>:
      PIN_NUMBER='(C26,0,0,0,0,0,0,0,0,0,0,0,0,0)';
      PINUSE='UNSPEC';
      NO_LOAD_CHECK='Both';
      NO_IO_CHECK='Both';
      NO_ASSERT_CHECK='TRUE';
      NO_DIR_CHECK='TRUE';
      ALLOW_CONNECT='TRUE';
    'RSVD'<59>:
      PIN_NUMBER='(0,0,0,0,0,0,0,0,AT27,0,0,0,0,0)';
      PINUSE='UNSPEC';
      NO_LOAD_CHECK='Both';
      NO_IO_CHECK='Both';
      NO_ASSERT_CHECK='TRUE';
      NO_DIR_CHECK='TRUE';
      ALLOW_CONNECT='TRUE';
    'RSVD'<58>:
      PIN_NUMBER='(0,0,0,0,0,0,0,0,AP27,0,0,0,0,0)';
      PINUSE='UNSPEC';
      NO_LOAD_CHECK='Both';
      NO_IO_CHECK='Both';
      NO_ASSERT_CHECK='TRUE';
      NO_DIR_CHECK='TRUE';
      ALLOW_CONNECT='TRUE';
    'RSVD'<55>:
      PIN_NUMBER='(0,BN68,0,0,0,0,0,0,0,0,0,0,0,0)';
      PINUSE='UNSPEC';
      NO_LOAD_CHECK='Both';
      NO_IO_CHECK='Both';
      NO_ASSERT_CHECK='TRUE';
      NO_DIR_CHECK='TRUE';
      ALLOW_CONNECT='TRUE';
    'RSVD'<54>:
      PIN_NUMBER='(0,0,0,0,R24,0,0,0,0,0,0,0,0,0)';
      PINUSE='UNSPEC';
      NO_LOAD_CHECK='Both';
      NO_IO_CHECK='Both';
      NO_ASSERT_CHECK='TRUE';
      NO_DIR_CHECK='TRUE';
      ALLOW_CONNECT='TRUE';
    'RSVD'<53>:
      PIN_NUMBER='(0,0,0,0,P26,0,0,0,0,0,0,0,0,0)';
      PINUSE='UNSPEC';
      NO_LOAD_CHECK='Both';
      NO_IO_CHECK='Both';
      NO_ASSERT_CHECK='TRUE';
      NO_DIR_CHECK='TRUE';
      ALLOW_CONNECT='TRUE';
    'RSVD'<52>:
      PIN_NUMBER='(0,0,AA71,0,0,0,0,0,0,0,0,0,0,0)';
      PINUSE='UNSPEC';
      NO_LOAD_CHECK='Both';
      NO_IO_CHECK='Both';
      NO_ASSERT_CHECK='TRUE';
      NO_DIR_CHECK='TRUE';
      ALLOW_CONNECT='TRUE';
    'RSVD'<51>:
      PIN_NUMBER='(0,0,AA69,0,0,0,0,0,0,0,0,0,0,0)';
      PINUSE='UNSPEC';
      NO_LOAD_CHECK='Both';
      NO_IO_CHECK='Both';
      NO_ASSERT_CHECK='TRUE';
      NO_DIR_CHECK='TRUE';
      ALLOW_CONNECT='TRUE';
    'RSVD'<50>:
      PIN_NUMBER='(0,0,H69,0,0,0,0,0,0,0,0,0,0,0)';
      PINUSE='UNSPEC';
      NO_LOAD_CHECK='Both';
      NO_IO_CHECK='Both';
      NO_ASSERT_CHECK='TRUE';
      NO_DIR_CHECK='TRUE';
      ALLOW_CONNECT='TRUE';
    'RSVD'<49>:
      PIN_NUMBER='(0,0,G67,0,0,0,0,0,0,0,0,0,0,0)';
      PINUSE='UNSPEC';
      NO_LOAD_CHECK='Both';
      NO_IO_CHECK='Both';
      NO_ASSERT_CHECK='TRUE';
      NO_DIR_CHECK='TRUE';
      ALLOW_CONNECT='TRUE';
    'RSVD'<48>:
      PIN_NUMBER='(0,0,AP71,0,0,0,0,0,0,0,0,0,0,0)';
      PINUSE='UNSPEC';
      NO_LOAD_CHECK='Both';
      NO_IO_CHECK='Both';
      NO_ASSERT_CHECK='TRUE';
      NO_DIR_CHECK='TRUE';
      ALLOW_CONNECT='TRUE';
    'RSVD'<47>:
      PIN_NUMBER='(0,0,AP69,0,0,0,0,0,0,0,0,0,0,0)';
      PINUSE='UNSPEC';
      NO_LOAD_CHECK='Both';
      NO_IO_CHECK='Both';
      NO_ASSERT_CHECK='TRUE';
      NO_DIR_CHECK='TRUE';
      ALLOW_CONNECT='TRUE';
    'RSVD'<46>:
      PIN_NUMBER='(0,0,0,0,0,0,0,BW3,0,0,0,0,0,0)';
      PINUSE='UNSPEC';
      NO_LOAD_CHECK='Both';
      NO_IO_CHECK='Both';
      NO_ASSERT_CHECK='TRUE';
      NO_DIR_CHECK='TRUE';
      ALLOW_CONNECT='TRUE';
    'RSVD'<45>:
      PIN_NUMBER='(0,0,0,0,P22,0,0,0,0,0,0,0,0,0)';
      PINUSE='UNSPEC';
      NO_LOAD_CHECK='Both';
      NO_IO_CHECK='Both';
      NO_ASSERT_CHECK='TRUE';
      NO_DIR_CHECK='TRUE';
      ALLOW_CONNECT='TRUE';
    'RSVD'<44>:
      PIN_NUMBER='(0,0,0,0,BN33,0,0,0,0,0,0,0,0,0)';
      PINUSE='UNSPEC';
      NO_LOAD_CHECK='Both';
      NO_IO_CHECK='Both';
      NO_ASSERT_CHECK='TRUE';
      NO_DIR_CHECK='TRUE';
      ALLOW_CONNECT='TRUE';
    'RSVD'<43>:
      PIN_NUMBER='(0,0,0,0,BL33,0,0,0,0,0,0,0,0,0)';
      PINUSE='UNSPEC';
      NO_LOAD_CHECK='Both';
      NO_IO_CHECK='Both';
      NO_ASSERT_CHECK='TRUE';
      NO_DIR_CHECK='TRUE';
      ALLOW_CONNECT='TRUE';
    'RSVD'<42>:
      PIN_NUMBER='(0,0,0,0,BG40,0,0,0,0,0,0,0,0,0)';
      PINUSE='UNSPEC';
      NO_LOAD_CHECK='Both';
      NO_IO_CHECK='Both';
      NO_ASSERT_CHECK='TRUE';
      NO_DIR_CHECK='TRUE';
      ALLOW_CONNECT='TRUE';
    'RSVD'<41>:
      PIN_NUMBER='(0,0,0,0,BJ40,0,0,0,0,0,0,0,0,0)';
      PINUSE='UNSPEC';
      NO_LOAD_CHECK='Both';
      NO_IO_CHECK='Both';
      NO_ASSERT_CHECK='TRUE';
      NO_DIR_CHECK='TRUE';
      ALLOW_CONNECT='TRUE';
    'RSVD'<40>:
      PIN_NUMBER='(0,0,0,0,BN26,0,0,0,0,0,0,0,0,0)';
      PINUSE='UNSPEC';
      NO_LOAD_CHECK='Both';
      NO_IO_CHECK='Both';
      NO_ASSERT_CHECK='TRUE';
      NO_DIR_CHECK='TRUE';
      ALLOW_CONNECT='TRUE';
    'RSVD'<39>:
      PIN_NUMBER='(0,0,0,0,BL26,0,0,0,0,0,0,0,0,0)';
      PINUSE='UNSPEC';
      NO_LOAD_CHECK='Both';
      NO_IO_CHECK='Both';
      NO_ASSERT_CHECK='TRUE';
      NO_DIR_CHECK='TRUE';
      ALLOW_CONNECT='TRUE';
    'RSVD'<38>:
      PIN_NUMBER='(0,0,0,0,BL29,0,0,0,0,0,0,0,0,0)';
      PINUSE='UNSPEC';
      NO_LOAD_CHECK='Both';
      NO_IO_CHECK='Both';
      NO_ASSERT_CHECK='TRUE';
      NO_DIR_CHECK='TRUE';
      ALLOW_CONNECT='TRUE';
    'RSVD'<37>:
      PIN_NUMBER='(0,0,0,0,BN29,0,0,0,0,0,0,0,0,0)';
      PINUSE='UNSPEC';
      NO_LOAD_CHECK='Both';
      NO_IO_CHECK='Both';
      NO_ASSERT_CHECK='TRUE';
      NO_DIR_CHECK='TRUE';
      ALLOW_CONNECT='TRUE';
    'RSVD'<36>:
      PIN_NUMBER='(0,0,0,0,AK54,0,0,0,0,0,0,0,0,0)';
      PINUSE='UNSPEC';
      NO_LOAD_CHECK='Both';
      NO_IO_CHECK='Both';
      NO_ASSERT_CHECK='TRUE';
      NO_DIR_CHECK='TRUE';
      ALLOW_CONNECT='TRUE';
    'RSVD'<35>:
      PIN_NUMBER='(0,0,0,0,W54,0,0,0,0,0,0,0,0,0)';
      PINUSE='UNSPEC';
      NO_LOAD_CHECK='Both';
      NO_IO_CHECK='Both';
      NO_ASSERT_CHECK='TRUE';
      NO_DIR_CHECK='TRUE';
      ALLOW_CONNECT='TRUE';
    'RSVD'<34>:
      PIN_NUMBER='(0,0,0,0,Y56,0,0,0,0,0,0,0,0,0)';
      PINUSE='UNSPEC';
      NO_LOAD_CHECK='Both';
      NO_IO_CHECK='Both';
      NO_ASSERT_CHECK='TRUE';
      NO_DIR_CHECK='TRUE';
      ALLOW_CONNECT='TRUE';
    'RSVD'<33>:
      PIN_NUMBER='(0,0,0,0,V56,0,0,0,0,0,0,0,0,0)';
      PINUSE='UNSPEC';
      NO_LOAD_CHECK='Both';
      NO_IO_CHECK='Both';
      NO_ASSERT_CHECK='TRUE';
      NO_DIR_CHECK='TRUE';
      ALLOW_CONNECT='TRUE';
    'RSVD'<32>:
      PIN_NUMBER='(0,0,0,0,AA54,0,0,0,0,0,0,0,0,0)';
      PINUSE='UNSPEC';
      NO_LOAD_CHECK='Both';
      NO_IO_CHECK='Both';
      NO_ASSERT_CHECK='TRUE';
      NO_DIR_CHECK='TRUE';
      ALLOW_CONNECT='TRUE';
    'RSVD'<31>:
      PIN_NUMBER='(0,0,0,0,0,0,0,0,P29,0,0,0,0,0)';
      PINUSE='UNSPEC';
      NO_LOAD_CHECK='Both';
      NO_IO_CHECK='Both';
      NO_ASSERT_CHECK='TRUE';
      NO_DIR_CHECK='TRUE';
      ALLOW_CONNECT='TRUE';
    'RSVD'<30>:
      PIN_NUMBER='(0,0,0,0,0,0,0,0,R31,0,0,0,0,0)';
      PINUSE='UNSPEC';
      NO_LOAD_CHECK='Both';
      NO_IO_CHECK='Both';
      NO_ASSERT_CHECK='TRUE';
      NO_DIR_CHECK='TRUE';
      ALLOW_CONNECT='TRUE';
    'RSVD'<29>:
      PIN_NUMBER='(0,0,0,0,0,0,0,0,P33,0,0,0,0,0)';
      PINUSE='UNSPEC';
      NO_LOAD_CHECK='Both';
      NO_IO_CHECK='Both';
      NO_ASSERT_CHECK='TRUE';
      NO_DIR_CHECK='TRUE';
      ALLOW_CONNECT='TRUE';
    'RSVD'<28>:
      PIN_NUMBER='(0,0,0,0,0,0,0,0,R35,0,0,0,0,0)';
      PINUSE='UNSPEC';
      NO_LOAD_CHECK='Both';
      NO_IO_CHECK='Both';
      NO_ASSERT_CHECK='TRUE';
      NO_DIR_CHECK='TRUE';
      ALLOW_CONNECT='TRUE';
    'RSVD'<27>:
      PIN_NUMBER='(0,0,0,0,0,0,0,BG26,0,0,0,0,0,0)';
      PINUSE='UNSPEC';
      NO_LOAD_CHECK='Both';
      NO_IO_CHECK='Both';
      NO_ASSERT_CHECK='TRUE';
      NO_DIR_CHECK='TRUE';
      ALLOW_CONNECT='TRUE';
    'RSVD'<26>:
      PIN_NUMBER='(0,0,0,0,0,0,0,BH24,0,0,0,0,0,0)';
      PINUSE='UNSPEC';
      NO_LOAD_CHECK='Both';
      NO_IO_CHECK='Both';
      NO_ASSERT_CHECK='TRUE';
      NO_DIR_CHECK='TRUE';
      ALLOW_CONNECT='TRUE';
    'RSVD'<25>:
      PIN_NUMBER='(0,0,0,0,0,0,0,P48,0,0,0,0,0,0)';
      PINUSE='UNSPEC';
      NO_LOAD_CHECK='Both';
      NO_IO_CHECK='Both';
      NO_ASSERT_CHECK='TRUE';
      NO_DIR_CHECK='TRUE';
      ALLOW_CONNECT='TRUE';
    'RSVD'<24>:
      PIN_NUMBER='(0,0,0,0,0,0,0,P44,0,0,0,0,0,0)';
      PINUSE='UNSPEC';
      NO_LOAD_CHECK='Both';
      NO_IO_CHECK='Both';
      NO_ASSERT_CHECK='TRUE';
      NO_DIR_CHECK='TRUE';
      ALLOW_CONNECT='TRUE';
    'RSVD'<23>:
      PIN_NUMBER='(0,0,0,0,0,0,0,P40,0,0,0,0,0,0)';
      PINUSE='UNSPEC';
      NO_LOAD_CHECK='Both';
      NO_IO_CHECK='Both';
      NO_ASSERT_CHECK='TRUE';
      NO_DIR_CHECK='TRUE';
      ALLOW_CONNECT='TRUE';
    'RSVD'<22>:
      PIN_NUMBER='(0,0,0,0,0,0,0,AT71,0,0,0,0,0,0)';
      PINUSE='UNSPEC';
      NO_LOAD_CHECK='Both';
      NO_IO_CHECK='Both';
      NO_ASSERT_CHECK='TRUE';
      NO_DIR_CHECK='TRUE';
      ALLOW_CONNECT='TRUE';
    'RSVD'<21>:
      PIN_NUMBER='(0,0,0,0,0,0,0,A11,0,0,0,0,0,0)';
      PINUSE='UNSPEC';
      NO_LOAD_CHECK='Both';
      NO_IO_CHECK='Both';
      NO_ASSERT_CHECK='TRUE';
      NO_DIR_CHECK='TRUE';
      ALLOW_CONNECT='TRUE';
    'RSVD'<20>:
      PIN_NUMBER='(0,0,0,0,0,0,0,D10,0,0,0,0,0,0)';
      PINUSE='UNSPEC';
      NO_LOAD_CHECK='Both';
      NO_IO_CHECK='Both';
      NO_ASSERT_CHECK='TRUE';
      NO_DIR_CHECK='TRUE';
      ALLOW_CONNECT='TRUE';
    'RSVD'<19>:
      PIN_NUMBER='(0,0,0,0,0,0,0,C9,0,0,0,0,0,0)';
      PINUSE='UNSPEC';
      NO_LOAD_CHECK='Both';
      NO_IO_CHECK='Both';
      NO_ASSERT_CHECK='TRUE';
      NO_DIR_CHECK='TRUE';
      ALLOW_CONNECT='TRUE';
    'RSVD'<18>:
      PIN_NUMBER='(0,0,0,0,0,0,0,C11,0,0,0,0,0,0)';
      PINUSE='UNSPEC';
      NO_LOAD_CHECK='Both';
      NO_IO_CHECK='Both';
      NO_ASSERT_CHECK='TRUE';
      NO_DIR_CHECK='TRUE';
      ALLOW_CONNECT='TRUE';
    'RSVD'<17>:
      PIN_NUMBER='(0,0,0,0,0,0,0,B10,0,0,0,0,0,0)';
      PINUSE='UNSPEC';
      NO_LOAD_CHECK='Both';
      NO_IO_CHECK='Both';
      NO_ASSERT_CHECK='TRUE';
      NO_DIR_CHECK='TRUE';
      ALLOW_CONNECT='TRUE';
    'RSVD'<16>:
      PIN_NUMBER='(0,0,0,0,0,0,0,C5,0,0,0,0,0,0)';
      PINUSE='UNSPEC';
      NO_LOAD_CHECK='Both';
      NO_IO_CHECK='Both';
      NO_ASSERT_CHECK='TRUE';
      NO_DIR_CHECK='TRUE';
      ALLOW_CONNECT='TRUE';
    'RSVD'<15>:
      PIN_NUMBER='(0,0,0,0,0,0,0,C6,0,0,0,0,0,0)';
      PINUSE='UNSPEC';
      NO_LOAD_CHECK='Both';
      NO_IO_CHECK='Both';
      NO_ASSERT_CHECK='TRUE';
      NO_DIR_CHECK='TRUE';
      ALLOW_CONNECT='TRUE';
    'RSVD'<14>:
      PIN_NUMBER='(0,0,0,0,0,0,0,E18,0,0,0,0,0,0)';
      PINUSE='UNSPEC';
      NO_LOAD_CHECK='Both';
      NO_IO_CHECK='Both';
      NO_ASSERT_CHECK='TRUE';
      NO_DIR_CHECK='TRUE';
      ALLOW_CONNECT='TRUE';
    'RSVD'<13>:
      PIN_NUMBER='(0,0,0,0,0,0,0,C67,0,0,0,0,0,0)';
      PINUSE='UNSPEC';
      NO_LOAD_CHECK='Both';
      NO_IO_CHECK='Both';
      NO_ASSERT_CHECK='TRUE';
      NO_DIR_CHECK='TRUE';
      ALLOW_CONNECT='TRUE';
    'RSVD'<12>:
      PIN_NUMBER='(0,0,0,0,0,0,0,C68,0,0,0,0,0,0)';
      PINUSE='UNSPEC';
      NO_LOAD_CHECK='Both';
      NO_IO_CHECK='Both';
      NO_ASSERT_CHECK='TRUE';
      NO_DIR_CHECK='TRUE';
      ALLOW_CONNECT='TRUE';
    'RSVD'<11>:
      PIN_NUMBER='(0,0,0,0,0,0,0,C18,0,0,0,0,0,0)';
      PINUSE='UNSPEC';
      NO_LOAD_CHECK='Both';
      NO_IO_CHECK='Both';
      NO_ASSERT_CHECK='TRUE';
      NO_DIR_CHECK='TRUE';
      ALLOW_CONNECT='TRUE';
    'RSVD'<10>:
      PIN_NUMBER='(0,0,0,0,0,0,0,D8,0,0,0,0,0,0)';
      PINUSE='UNSPEC';
      NO_LOAD_CHECK='Both';
      NO_IO_CHECK='Both';
      NO_ASSERT_CHECK='TRUE';
      NO_DIR_CHECK='TRUE';
      ALLOW_CONNECT='TRUE';
    'RSVD'<9>:
      PIN_NUMBER='(0,0,0,0,0,0,0,F66,0,0,0,0,0,0)';
      PINUSE='UNSPEC';
      NO_LOAD_CHECK='Both';
      NO_IO_CHECK='Both';
      NO_ASSERT_CHECK='TRUE';
      NO_DIR_CHECK='TRUE';
      ALLOW_CONNECT='TRUE';
    'RSVD'<8>:
      PIN_NUMBER='(0,0,0,0,0,0,0,F69,0,0,0,0,0,0)';
      PINUSE='UNSPEC';
      NO_LOAD_CHECK='Both';
      NO_IO_CHECK='Both';
      NO_ASSERT_CHECK='TRUE';
      NO_DIR_CHECK='TRUE';
      ALLOW_CONNECT='TRUE';
    'RSVD'<7>:
      PIN_NUMBER='(0,0,0,0,0,0,0,F8,0,0,0,0,0,0)';
      PINUSE='UNSPEC';
      NO_LOAD_CHECK='Both';
      NO_IO_CHECK='Both';
      NO_ASSERT_CHECK='TRUE';
      NO_DIR_CHECK='TRUE';
      ALLOW_CONNECT='TRUE';
    'RSVD'<6>:
      PIN_NUMBER='(0,0,0,0,0,0,0,AT69,0,0,0,0,0,0)';
      PINUSE='UNSPEC';
      NO_LOAD_CHECK='Both';
      NO_IO_CHECK='Both';
      NO_ASSERT_CHECK='TRUE';
      NO_DIR_CHECK='TRUE';
      ALLOW_CONNECT='TRUE';
    'RSVD'<5>:
      PIN_NUMBER='(0,0,0,0,0,0,0,AG15,0,0,0,0,0,0)';
      PINUSE='UNSPEC';
      NO_LOAD_CHECK='Both';
      NO_IO_CHECK='Both';
      NO_ASSERT_CHECK='TRUE';
      NO_DIR_CHECK='TRUE';
      ALLOW_CONNECT='TRUE';
    'RSVD'<4>:
      PIN_NUMBER='(0,0,0,0,0,0,0,P37,0,0,0,0,0,0)';
      PINUSE='UNSPEC';
      NO_LOAD_CHECK='Both';
      NO_IO_CHECK='Both';
      NO_ASSERT_CHECK='TRUE';
      NO_DIR_CHECK='TRUE';
      ALLOW_CONNECT='TRUE';
    'RSVD'<3>:
      PIN_NUMBER='(0,0,0,0,0,0,0,V11,0,0,0,0,0,0)';
      PINUSE='UNSPEC';
      NO_LOAD_CHECK='Both';
      NO_IO_CHECK='Both';
      NO_ASSERT_CHECK='TRUE';
      NO_DIR_CHECK='TRUE';
      ALLOW_CONNECT='TRUE';
    'RSVD'<2>:
      PIN_NUMBER='(0,0,0,0,0,0,0,AA58,0,0,0,0,0,0)';
      PINUSE='UNSPEC';
      NO_LOAD_CHECK='Both';
      NO_IO_CHECK='Both';
      NO_ASSERT_CHECK='TRUE';
      NO_DIR_CHECK='TRUE';
      ALLOW_CONNECT='TRUE';
    'RSVD'<1>:
      PIN_NUMBER='(0,0,0,0,0,0,0,AC56,0,0,0,0,0,0)';
      PINUSE='UNSPEC';
      NO_LOAD_CHECK='Both';
      NO_IO_CHECK='Both';
      NO_ASSERT_CHECK='TRUE';
      NO_DIR_CHECK='TRUE';
      ALLOW_CONNECT='TRUE';
    'RSVD'<0>:
      PIN_NUMBER='(0,0,0,0,0,0,0,AF61,0,0,0,0,0,0)';
      PINUSE='UNSPEC';
      NO_LOAD_CHECK='Both';
      NO_IO_CHECK='Both';
      NO_ASSERT_CHECK='TRUE';
      NO_DIR_CHECK='TRUE';
      ALLOW_CONNECT='TRUE';
    'RTCRST_N':
      PIN_NUMBER='(0,0,0,0,0,0,0,P11,0,0,0,0,0,0)';
      BIDIRECTIONAL='TRUE';
      INPUT_LOAD='(-0.01,0.01)';
      OUTPUT_LOAD='(1.0,-1.0)';
    'RTCX1':
      PIN_NUMBER='(K17,0,0,0,0,0,0,0,0,0,0,0,0,0)';
      BIDIRECTIONAL='TRUE';
      INPUT_LOAD='(-0.01,0.01)';
      OUTPUT_LOAD='(1.0,-1.0)';
    'RTCX2':
      PIN_NUMBER='(H17,0,0,0,0,0,0,0,0,0,0,0,0,0)';
      BIDIRECTIONAL='TRUE';
      INPUT_LOAD='(-0.01,0.01)';
      OUTPUT_LOAD='(1.0,-1.0)';
    'SLP_GBE_N':
      PIN_NUMBER='(0,0,0,0,M15,0,0,0,0,0,0,0,0,0)';
      BIDIRECTIONAL='TRUE';
      INPUT_LOAD='(-0.01,0.01)';
      OUTPUT_LOAD='(1.0,-1.0)';
    'SLP_SUS_N':
      PIN_NUMBER='(0,0,0,0,P7,0,0,0,0,0,0,0,0,0)';
      BIDIRECTIONAL='TRUE';
      INPUT_LOAD='(-0.01,0.01)';
      OUTPUT_LOAD='(1.0,-1.0)';
    'SPI0_CLK':
      PIN_NUMBER='(0,0,0,0,0,0,0,K2,0,0,0,0,0,0)';
      BIDIRECTIONAL='TRUE';
      INPUT_LOAD='(-0.01,0.01)';
      OUTPUT_LOAD='(1.0,-1.0)';
    'SPI0_FLASH_CS0_N':
      PIN_NUMBER='(0,0,0,0,0,0,0,J3,0,0,0,0,0,0)';
      BIDIRECTIONAL='TRUE';
      INPUT_LOAD='(-0.01,0.01)';
      OUTPUT_LOAD='(1.0,-1.0)';
    'SPI0_FLASH_CS1_N':
      PIN_NUMBER='(0,0,0,0,0,0,0,G7,0,0,0,0,0,0)';
      BIDIRECTIONAL='TRUE';
      INPUT_LOAD='(-0.01,0.01)';
      OUTPUT_LOAD='(1.0,-1.0)';
    'SPI0_IO2':
      PIN_NUMBER='(0,0,0,0,0,0,0,F5,0,0,0,0,0,0)';
      BIDIRECTIONAL='TRUE';
      INPUT_LOAD='(-0.01,0.01)';
      OUTPUT_LOAD='(1.0,-1.0)';
    'SPI0_IO3':
      PIN_NUMBER='(0,0,0,0,0,0,0,L1,0,0,0,0,0,0)';
      BIDIRECTIONAL='TRUE';
      INPUT_LOAD='(-0.01,0.01)';
      OUTPUT_LOAD='(1.0,-1.0)';
    'SPI0_MISO_IO1':
      PIN_NUMBER='(0,0,0,0,0,0,0,L3,0,0,0,0,0,0)';
      BIDIRECTIONAL='TRUE';
      INPUT_LOAD='(-0.01,0.01)';
      OUTPUT_LOAD='(1.0,-1.0)';
    'SPI0_MOSI_IO0':
      PIN_NUMBER='(0,0,0,0,0,0,0,H4,0,0,0,0,0,0)';
      BIDIRECTIONAL='TRUE';
      INPUT_LOAD='(-0.01,0.01)';
      OUTPUT_LOAD='(1.0,-1.0)';
    'SPI0_TPM_CS_N':
      PIN_NUMBER='(0,0,0,0,0,0,0,K4,0,0,0,0,0,0)';
      BIDIRECTIONAL='TRUE';
      INPUT_LOAD='(-0.01,0.01)';
      OUTPUT_LOAD='(1.0,-1.0)';
    'SRTCRST_N':
      PIN_NUMBER='(0,0,0,0,0,0,0,G18,0,0,0,0,0,0)';
      BIDIRECTIONAL='TRUE';
      INPUT_LOAD='(-0.01,0.01)';
      OUTPUT_LOAD='(1.0,-1.0)';
    'SYS_PWROK':
      PIN_NUMBER='(0,0,0,0,BY19,0,0,0,0,0,0,0,0,0)';
      BIDIRECTIONAL='TRUE';
      INPUT_LOAD='(-0.01,0.01)';
      OUTPUT_LOAD='(1.0,-1.0)';
    'SYS_RESET_N':
      PIN_NUMBER='(0,0,0,0,BV19,0,0,0,0,0,0,0,0,0)';
      BIDIRECTIONAL='TRUE';
      INPUT_LOAD='(-0.01,0.01)';
      OUTPUT_LOAD='(1.0,-1.0)';
    'THRMTRIP_N':
      PIN_NUMBER='(0,0,0,0,V15,0,0,0,0,0,0,0,0,0)';
      BIDIRECTIONAL='TRUE';
      INPUT_LOAD='(-0.01,0.01)';
      OUTPUT_LOAD='(1.0,-1.0)';
    'TRIGGER_IN':
      PIN_NUMBER='(0,0,0,0,M7,0,0,0,0,0,0,0,0,0)';
      BIDIRECTIONAL='TRUE';
      INPUT_LOAD='(-0.01,0.01)';
      OUTPUT_LOAD='(1.0,-1.0)';
    'TRIGGER_OUT':
      PIN_NUMBER='(0,0,0,0,R13,0,0,0,0,0,0,0,0,0)';
      BIDIRECTIONAL='TRUE';
      INPUT_LOAD='(-0.01,0.01)';
      OUTPUT_LOAD='(1.0,-1.0)';
    'USB2N_1':
      PIN_NUMBER='(0,BY60,0,0,0,0,0,0,0,0,0,0,0,0)';
      BIDIRECTIONAL='TRUE';
      INPUT_LOAD='(-0.01,0.01)';
      OUTPUT_LOAD='(1.0,-1.0)';
    'USB2N_10':
      PIN_NUMBER='(0,BW65,0,0,0,0,0,0,0,0,0,0,0,0)';
      BIDIRECTIONAL='TRUE';
      INPUT_LOAD='(-0.01,0.01)';
      OUTPUT_LOAD='(1.0,-1.0)';
    'USB2N_11':
      PIN_NUMBER='(0,CA54,0,0,0,0,0,0,0,0,0,0,0,0)';
      BIDIRECTIONAL='TRUE';
      INPUT_LOAD='(-0.01,0.01)';
      OUTPUT_LOAD='(1.0,-1.0)';
    'USB2N_12':
      PIN_NUMBER='(0,BW67,0,0,0,0,0,0,0,0,0,0,0,0)';
      BIDIRECTIONAL='TRUE';
      INPUT_LOAD='(-0.01,0.01)';
      OUTPUT_LOAD='(1.0,-1.0)';
    'USB2N_13':
      PIN_NUMBER='(0,BY53,0,0,0,0,0,0,0,0,0,0,0,0)';
      BIDIRECTIONAL='TRUE';
      INPUT_LOAD='(-0.01,0.01)';
      OUTPUT_LOAD='(1.0,-1.0)';
    'USB2N_14':
      PIN_NUMBER='(0,BW68,0,0,0,0,0,0,0,0,0,0,0,0)';
      BIDIRECTIONAL='TRUE';
      INPUT_LOAD='(-0.01,0.01)';
      OUTPUT_LOAD='(1.0,-1.0)';
    'USB2N_2':
      PIN_NUMBER='(0,CA61,0,0,0,0,0,0,0,0,0,0,0,0)';
      BIDIRECTIONAL='TRUE';
      INPUT_LOAD='(-0.01,0.01)';
      OUTPUT_LOAD='(1.0,-1.0)';
    'USB2N_3':
      PIN_NUMBER='(0,CA59,0,0,0,0,0,0,0,0,0,0,0,0)';
      BIDIRECTIONAL='TRUE';
      INPUT_LOAD='(-0.01,0.01)';
      OUTPUT_LOAD='(1.0,-1.0)';
    'USB2N_4':
      PIN_NUMBER='(0,BY62,0,0,0,0,0,0,0,0,0,0,0,0)';
      BIDIRECTIONAL='TRUE';
      INPUT_LOAD='(-0.01,0.01)';
      OUTPUT_LOAD='(1.0,-1.0)';
    'USB2N_5':
      PIN_NUMBER='(0,BY58,0,0,0,0,0,0,0,0,0,0,0,0)';
      BIDIRECTIONAL='TRUE';
      INPUT_LOAD='(-0.01,0.01)';
      OUTPUT_LOAD='(1.0,-1.0)';
    'USB2N_6':
      PIN_NUMBER='(0,CA63,0,0,0,0,0,0,0,0,0,0,0,0)';
      BIDIRECTIONAL='TRUE';
      INPUT_LOAD='(-0.01,0.01)';
      OUTPUT_LOAD='(1.0,-1.0)';
    'USB2N_7':
      PIN_NUMBER='(0,CA57,0,0,0,0,0,0,0,0,0,0,0,0)';
      BIDIRECTIONAL='TRUE';
      INPUT_LOAD='(-0.01,0.01)';
      OUTPUT_LOAD='(1.0,-1.0)';
    'USB2N_8':
      PIN_NUMBER='(0,BY64,0,0,0,0,0,0,0,0,0,0,0,0)';
      BIDIRECTIONAL='TRUE';
      INPUT_LOAD='(-0.01,0.01)';
      OUTPUT_LOAD='(1.0,-1.0)';
    'USB2N_9':
      PIN_NUMBER='(0,BY55,0,0,0,0,0,0,0,0,0,0,0,0)';
      BIDIRECTIONAL='TRUE';
      INPUT_LOAD='(-0.01,0.01)';
      OUTPUT_LOAD='(1.0,-1.0)';
    'USB2P_1':
      PIN_NUMBER='(0,BV60,0,0,0,0,0,0,0,0,0,0,0,0)';
      BIDIRECTIONAL='TRUE';
      INPUT_LOAD='(-0.01,0.01)';
      OUTPUT_LOAD='(1.0,-1.0)';
    'USB2P_10':
      PIN_NUMBER='(0,BU65,0,0,0,0,0,0,0,0,0,0,0,0)';
      BIDIRECTIONAL='TRUE';
      INPUT_LOAD='(-0.01,0.01)';
      OUTPUT_LOAD='(1.0,-1.0)';
    'USB2P_11':
      PIN_NUMBER='(0,BW54,0,0,0,0,0,0,0,0,0,0,0,0)';
      BIDIRECTIONAL='TRUE';
      INPUT_LOAD='(-0.01,0.01)';
      OUTPUT_LOAD='(1.0,-1.0)';
    'USB2P_12':
      PIN_NUMBER='(0,BV66,0,0,0,0,0,0,0,0,0,0,0,0)';
      BIDIRECTIONAL='TRUE';
      INPUT_LOAD='(-0.01,0.01)';
      OUTPUT_LOAD='(1.0,-1.0)';
    'USB2P_13':
      PIN_NUMBER='(0,BV53,0,0,0,0,0,0,0,0,0,0,0,0)';
      BIDIRECTIONAL='TRUE';
      INPUT_LOAD='(-0.01,0.01)';
      OUTPUT_LOAD='(1.0,-1.0)';
    'USB2P_14':
      PIN_NUMBER='(0,BU67,0,0,0,0,0,0,0,0,0,0,0,0)';
      BIDIRECTIONAL='TRUE';
      INPUT_LOAD='(-0.01,0.01)';
      OUTPUT_LOAD='(1.0,-1.0)';
    'USB2P_2':
      PIN_NUMBER='(0,BW61,0,0,0,0,0,0,0,0,0,0,0,0)';
      BIDIRECTIONAL='TRUE';
      INPUT_LOAD='(-0.01,0.01)';
      OUTPUT_LOAD='(1.0,-1.0)';
    'USB2P_3':
      PIN_NUMBER='(0,BW59,0,0,0,0,0,0,0,0,0,0,0,0)';
      BIDIRECTIONAL='TRUE';
      INPUT_LOAD='(-0.01,0.01)';
      OUTPUT_LOAD='(1.0,-1.0)';
    'USB2P_4':
      PIN_NUMBER='(0,BV62,0,0,0,0,0,0,0,0,0,0,0,0)';
      BIDIRECTIONAL='TRUE';
      INPUT_LOAD='(-0.01,0.01)';
      OUTPUT_LOAD='(1.0,-1.0)';
    'USB2P_5':
      PIN_NUMBER='(0,BV58,0,0,0,0,0,0,0,0,0,0,0,0)';
      BIDIRECTIONAL='TRUE';
      INPUT_LOAD='(-0.01,0.01)';
      OUTPUT_LOAD='(1.0,-1.0)';
    'USB2P_6':
      PIN_NUMBER='(0,BW63,0,0,0,0,0,0,0,0,0,0,0,0)';
      BIDIRECTIONAL='TRUE';
      INPUT_LOAD='(-0.01,0.01)';
      OUTPUT_LOAD='(1.0,-1.0)';
    'USB2P_7':
      PIN_NUMBER='(0,BW57,0,0,0,0,0,0,0,0,0,0,0,0)';
      BIDIRECTIONAL='TRUE';
      INPUT_LOAD='(-0.01,0.01)';
      OUTPUT_LOAD='(1.0,-1.0)';
    'USB2P_8':
      PIN_NUMBER='(0,BV64,0,0,0,0,0,0,0,0,0,0,0,0)';
      BIDIRECTIONAL='TRUE';
      INPUT_LOAD='(-0.01,0.01)';
      OUTPUT_LOAD='(1.0,-1.0)';
    'USB2P_9':
      PIN_NUMBER='(0,BV55,0,0,0,0,0,0,0,0,0,0,0,0)';
      BIDIRECTIONAL='TRUE';
      INPUT_LOAD='(-0.01,0.01)';
      OUTPUT_LOAD='(1.0,-1.0)';
    'USB2_COMP':
      PIN_NUMBER='(0,BN70,0,0,0,0,0,0,0,0,0,0,0,0)';
      BIDIRECTIONAL='TRUE';
      INPUT_LOAD='(-0.01,0.01)';
      OUTPUT_LOAD='(1.0,-1.0)';
    'USB2_VBUS':
      PIN_NUMBER='(0,BR67,0,0,0,0,0,0,0,0,0,0,0,0)';
      BIDIRECTIONAL='TRUE';
      INPUT_LOAD='(-0.01,0.01)';
      OUTPUT_LOAD='(1.0,-1.0)';
    'USB3_10_PCIE3_GBE_RXN':
      PIN_NUMBER='(0,0,AV72,0,0,0,0,0,0,0,0,0,0,0)';
      BIDIRECTIONAL='TRUE';
      INPUT_LOAD='(-0.01,0.01)';
      OUTPUT_LOAD='(1.0,-1.0)';
    'USB3_10_PCIE3_GBE_RXP':
      PIN_NUMBER='(0,0,AV70,0,0,0,0,0,0,0,0,0,0,0)';
      BIDIRECTIONAL='TRUE';
      INPUT_LOAD='(-0.01,0.01)';
      OUTPUT_LOAD='(1.0,-1.0)';
    'USB3_10_PCIE3_GBE_TXN':
      PIN_NUMBER='(0,0,BH61,0,0,0,0,0,0,0,0,0,0,0)';
      BIDIRECTIONAL='TRUE';
      INPUT_LOAD='(-0.01,0.01)';
      OUTPUT_LOAD='(1.0,-1.0)';
    'USB3_10_PCIE3_GBE_TXP':
      PIN_NUMBER='(0,0,BK61,0,0,0,0,0,0,0,0,0,0,0)';
      BIDIRECTIONAL='TRUE';
      INPUT_LOAD='(-0.01,0.01)';
      OUTPUT_LOAD='(1.0,-1.0)';
    'USB3_1_RXN':
      PIN_NUMBER='(0,BK71,0,0,0,0,0,0,0,0,0,0,0,0)';
      BIDIRECTIONAL='TRUE';
      INPUT_LOAD='(-0.01,0.01)';
      OUTPUT_LOAD='(1.0,-1.0)';
    'USB3_1_RXP':
      PIN_NUMBER='(0,BK69,0,0,0,0,0,0,0,0,0,0,0,0)';
      BIDIRECTIONAL='TRUE';
      INPUT_LOAD='(-0.01,0.01)';
      OUTPUT_LOAD='(1.0,-1.0)';
    'USB3_1_TXN':
      PIN_NUMBER='(0,BL52,0,0,0,0,0,0,0,0,0,0,0,0)';
      BIDIRECTIONAL='TRUE';
      INPUT_LOAD='(-0.01,0.01)';
      OUTPUT_LOAD='(1.0,-1.0)';
    'USB3_1_TXP':
      PIN_NUMBER='(0,BK54,0,0,0,0,0,0,0,0,0,0,0,0)';
      BIDIRECTIONAL='TRUE';
      INPUT_LOAD='(-0.01,0.01)';
      OUTPUT_LOAD='(1.0,-1.0)';
    'USB3_2_RXN':
      PIN_NUMBER='(0,BJ72,0,0,0,0,0,0,0,0,0,0,0,0)';
      BIDIRECTIONAL='TRUE';
      INPUT_LOAD='(-0.01,0.01)';
      OUTPUT_LOAD='(1.0,-1.0)';
    'USB3_2_RXP':
      PIN_NUMBER='(0,BJ70,0,0,0,0,0,0,0,0,0,0,0,0)';
      BIDIRECTIONAL='TRUE';
      INPUT_LOAD='(-0.01,0.01)';
      OUTPUT_LOAD='(1.0,-1.0)';
    'USB3_2_TXN':
      PIN_NUMBER='(0,BL56,0,0,0,0,0,0,0,0,0,0,0,0)';
      BIDIRECTIONAL='TRUE';
      INPUT_LOAD='(-0.01,0.01)';
      OUTPUT_LOAD='(1.0,-1.0)';
    'USB3_2_TXP':
      PIN_NUMBER='(0,BJ56,0,0,0,0,0,0,0,0,0,0,0,0)';
      BIDIRECTIONAL='TRUE';
      INPUT_LOAD='(-0.01,0.01)';
      OUTPUT_LOAD='(1.0,-1.0)';
    'USB3_3_RXN':
      PIN_NUMBER='(0,BH71,0,0,0,0,0,0,0,0,0,0,0,0)';
      BIDIRECTIONAL='TRUE';
      INPUT_LOAD='(-0.01,0.01)';
      OUTPUT_LOAD='(1.0,-1.0)';
    'USB3_3_RXP':
      PIN_NUMBER='(0,BH69,0,0,0,0,0,0,0,0,0,0,0,0)';
      BIDIRECTIONAL='TRUE';
      INPUT_LOAD='(-0.01,0.01)';
      OUTPUT_LOAD='(1.0,-1.0)';
    'USB3_3_TXN':
      PIN_NUMBER='(0,BM54,0,0,0,0,0,0,0,0,0,0,0,0)';
      BIDIRECTIONAL='TRUE';
      INPUT_LOAD='(-0.01,0.01)';
      OUTPUT_LOAD='(1.0,-1.0)';
    'USB3_3_TXP':
      PIN_NUMBER='(0,BN56,0,0,0,0,0,0,0,0,0,0,0,0)';
      BIDIRECTIONAL='TRUE';
      INPUT_LOAD='(-0.01,0.01)';
      OUTPUT_LOAD='(1.0,-1.0)';
    'USB3_4_RXN':
      PIN_NUMBER='(0,BF72,0,0,0,0,0,0,0,0,0,0,0,0)';
      BIDIRECTIONAL='TRUE';
      INPUT_LOAD='(-0.01,0.01)';
      OUTPUT_LOAD='(1.0,-1.0)';
    'USB3_4_RXP':
      PIN_NUMBER='(0,BF70,0,0,0,0,0,0,0,0,0,0,0,0)';
      BIDIRECTIONAL='TRUE';
      INPUT_LOAD='(-0.01,0.01)';
      OUTPUT_LOAD='(1.0,-1.0)';
    'USB3_4_TXN':
      PIN_NUMBER='(0,BH58,0,0,0,0,0,0,0,0,0,0,0,0)';
      BIDIRECTIONAL='TRUE';
      INPUT_LOAD='(-0.01,0.01)';
      OUTPUT_LOAD='(1.0,-1.0)';
    'USB3_4_TXP':
      PIN_NUMBER='(0,BG56,0,0,0,0,0,0,0,0,0,0,0,0)';
      BIDIRECTIONAL='TRUE';
      INPUT_LOAD='(-0.01,0.01)';
      OUTPUT_LOAD='(1.0,-1.0)';
    'USB3_5_RXN':
      PIN_NUMBER='(0,BE71,0,0,0,0,0,0,0,0,0,0,0,0)';
      BIDIRECTIONAL='TRUE';
      INPUT_LOAD='(-0.01,0.01)';
      OUTPUT_LOAD='(1.0,-1.0)';
    'USB3_5_RXP':
      PIN_NUMBER='(0,BE69,0,0,0,0,0,0,0,0,0,0,0,0)';
      BIDIRECTIONAL='TRUE';
      INPUT_LOAD='(-0.01,0.01)';
      OUTPUT_LOAD='(1.0,-1.0)';
    'USB3_5_TXN':
      PIN_NUMBER='(0,BK58,0,0,0,0,0,0,0,0,0,0,0,0)';
      BIDIRECTIONAL='TRUE';
      INPUT_LOAD='(-0.01,0.01)';
      OUTPUT_LOAD='(1.0,-1.0)';
    'USB3_5_TXP':
      PIN_NUMBER='(0,BJ59,0,0,0,0,0,0,0,0,0,0,0,0)';
      BIDIRECTIONAL='TRUE';
      INPUT_LOAD='(-0.01,0.01)';
      OUTPUT_LOAD='(1.0,-1.0)';
    'USB3_6_RXN':
      PIN_NUMBER='(0,BD72,0,0,0,0,0,0,0,0,0,0,0,0)';
      BIDIRECTIONAL='TRUE';
      INPUT_LOAD='(-0.01,0.01)';
      OUTPUT_LOAD='(1.0,-1.0)';
    'USB3_6_RXP':
      PIN_NUMBER='(0,BD70,0,0,0,0,0,0,0,0,0,0,0,0)';
      BIDIRECTIONAL='TRUE';
      INPUT_LOAD='(-0.01,0.01)';
      OUTPUT_LOAD='(1.0,-1.0)';
    'USB3_6_TXN':
      PIN_NUMBER='(0,BL59,0,0,0,0,0,0,0,0,0,0,0,0)';
      BIDIRECTIONAL='TRUE';
      INPUT_LOAD='(-0.01,0.01)';
      OUTPUT_LOAD='(1.0,-1.0)';
    'USB3_6_TXP':
      PIN_NUMBER='(0,BM61,0,0,0,0,0,0,0,0,0,0,0,0)';
      BIDIRECTIONAL='TRUE';
      INPUT_LOAD='(-0.01,0.01)';
      OUTPUT_LOAD='(1.0,-1.0)';
    'USB3_7_PCIE0_RXN':
      PIN_NUMBER='(0,0,BA71,0,0,0,0,0,0,0,0,0,0,0)';
      BIDIRECTIONAL='TRUE';
      INPUT_LOAD='(-0.01,0.01)';
      OUTPUT_LOAD='(1.0,-1.0)';
    'USB3_7_PCIE0_RXP':
      PIN_NUMBER='(0,0,BA69,0,0,0,0,0,0,0,0,0,0,0)';
      BIDIRECTIONAL='TRUE';
      INPUT_LOAD='(-0.01,0.01)';
      OUTPUT_LOAD='(1.0,-1.0)';
    'USB3_7_PCIE0_TXN':
      PIN_NUMBER='(0,0,BR61,0,0,0,0,0,0,0,0,0,0,0)';
      BIDIRECTIONAL='TRUE';
      INPUT_LOAD='(-0.01,0.01)';
      OUTPUT_LOAD='(1.0,-1.0)';
    'USB3_7_PCIE0_TXP':
      PIN_NUMBER='(0,0,BN63,0,0,0,0,0,0,0,0,0,0,0)';
      BIDIRECTIONAL='TRUE';
      INPUT_LOAD='(-0.01,0.01)';
      OUTPUT_LOAD='(1.0,-1.0)';
    'USB3_8_PCIE1_RXN':
      PIN_NUMBER='(0,0,AY72,0,0,0,0,0,0,0,0,0,0,0)';
      BIDIRECTIONAL='TRUE';
      INPUT_LOAD='(-0.01,0.01)';
      OUTPUT_LOAD='(1.0,-1.0)';
    'USB3_8_PCIE1_RXP':
      PIN_NUMBER='(0,0,AY70,0,0,0,0,0,0,0,0,0,0,0)';
      BIDIRECTIONAL='TRUE';
      INPUT_LOAD='(-0.01,0.01)';
      OUTPUT_LOAD='(1.0,-1.0)';
    'USB3_8_PCIE1_TXN':
      PIN_NUMBER='(0,0,BM65,0,0,0,0,0,0,0,0,0,0,0)';
      BIDIRECTIONAL='TRUE';
      INPUT_LOAD='(-0.01,0.01)';
      OUTPUT_LOAD='(1.0,-1.0)';
    'USB3_8_PCIE1_TXP':
      PIN_NUMBER='(0,0,BR65,0,0,0,0,0,0,0,0,0,0,0)';
      BIDIRECTIONAL='TRUE';
      INPUT_LOAD='(-0.01,0.01)';
      OUTPUT_LOAD='(1.0,-1.0)';
    'USB3_9_PCIE2_RXN':
      PIN_NUMBER='(0,0,AW71,0,0,0,0,0,0,0,0,0,0,0)';
      BIDIRECTIONAL='TRUE';
      INPUT_LOAD='(-0.01,0.01)';
      OUTPUT_LOAD='(1.0,-1.0)';
    'USB3_9_PCIE2_RXP':
      PIN_NUMBER='(0,0,AW69,0,0,0,0,0,0,0,0,0,0,0)';
      BIDIRECTIONAL='TRUE';
      INPUT_LOAD='(-0.01,0.01)';
      OUTPUT_LOAD='(1.0,-1.0)';
    'USB3_9_PCIE2_TXN':
      PIN_NUMBER='(0,0,BK65,0,0,0,0,0,0,0,0,0,0,0)';
      BIDIRECTIONAL='TRUE';
      INPUT_LOAD='(-0.01,0.01)';
      OUTPUT_LOAD='(1.0,-1.0)';
    'USB3_9_PCIE2_TXP':
      PIN_NUMBER='(0,0,BL66,0,0,0,0,0,0,0,0,0,0,0)';
      BIDIRECTIONAL='TRUE';
      INPUT_LOAD='(-0.01,0.01)';
      OUTPUT_LOAD='(1.0,-1.0)';
    'VCCA_CLKFILT_1P05'<4>:
      PIN_NUMBER='(0,0,0,0,0,0,0,0,AE46,0,0,0,0,0)';
      PINUSE='POWER';
      NO_LOAD_CHECK='Both';
      NO_IO_CHECK='Both';
      NO_ASSERT_CHECK='TRUE';
      NO_DIR_CHECK='TRUE';
      ALLOW_CONNECT='TRUE';
    'VCCA_CLKFILT_1P05'<3>:
      PIN_NUMBER='(0,0,0,0,0,0,0,0,AJ48,0,0,0,0,0)';
      PINUSE='POWER';
      NO_LOAD_CHECK='Both';
      NO_IO_CHECK='Both';
      NO_ASSERT_CHECK='TRUE';
      NO_DIR_CHECK='TRUE';
      ALLOW_CONNECT='TRUE';
    'VCCA_CLKFILT_1P05'<2>:
      PIN_NUMBER='(0,0,0,0,0,0,0,0,AJ46,0,0,0,0,0)';
      PINUSE='POWER';
      NO_LOAD_CHECK='Both';
      NO_IO_CHECK='Both';
      NO_ASSERT_CHECK='TRUE';
      NO_DIR_CHECK='TRUE';
      ALLOW_CONNECT='TRUE';
    'VCCA_CLKFILT_1P05'<1>:
      PIN_NUMBER='(0,0,0,0,0,0,0,0,AG45,0,0,0,0,0)';
      PINUSE='POWER';
      NO_LOAD_CHECK='Both';
      NO_IO_CHECK='Both';
      NO_ASSERT_CHECK='TRUE';
      NO_DIR_CHECK='TRUE';
      ALLOW_CONNECT='TRUE';
    'VCCA_CLKFILT_1P05'<0>:
      PIN_NUMBER='(0,0,0,0,0,0,0,0,W50,0,0,0,0,0)';
      PINUSE='POWER';
      NO_LOAD_CHECK='Both';
      NO_IO_CHECK='Both';
      NO_ASSERT_CHECK='TRUE';
      NO_DIR_CHECK='TRUE';
      ALLOW_CONNECT='TRUE';
    'VCCA_CLKUNF_1P05'<1>:
      PIN_NUMBER='(0,0,0,0,0,0,0,0,U50,0,0,0,0,0)';
      PINUSE='POWER';
      NO_LOAD_CHECK='Both';
      NO_IO_CHECK='Both';
      NO_ASSERT_CHECK='TRUE';
      NO_DIR_CHECK='TRUE';
      ALLOW_CONNECT='TRUE';
    'VCCA_CLKUNF_1P05'<0>:
      PIN_NUMBER='(0,0,0,0,0,0,0,0,AH50,0,0,0,0,0)';
      PINUSE='POWER';
      NO_LOAD_CHECK='Both';
      NO_IO_CHECK='Both';
      NO_ASSERT_CHECK='TRUE';
      NO_DIR_CHECK='TRUE';
      ALLOW_CONNECT='TRUE';
    'VCCA_CLKXTAL_1P05':
      PIN_NUMBER='(0,0,0,0,0,0,0,0,AD50,0,0,0,0,0)';
      PINUSE='POWER';
      NO_LOAD_CHECK='Both';
      NO_IO_CHECK='Both';
      NO_ASSERT_CHECK='TRUE';
      NO_DIR_CHECK='TRUE';
      ALLOW_CONNECT='TRUE';
    'VCCA_PLL0_1P05':
      PIN_NUMBER='(0,0,0,0,0,0,0,0,AG48,0,0,0,0,0)';
      PINUSE='POWER';
      NO_LOAD_CHECK='Both';
      NO_IO_CHECK='Both';
      NO_ASSERT_CHECK='TRUE';
      NO_DIR_CHECK='TRUE';
      ALLOW_CONNECT='TRUE';
    'VCCA_PLL1_1P05':
      PIN_NUMBER='(0,0,0,0,0,0,0,0,AE45,0,0,0,0,0)';
      PINUSE='POWER';
      NO_LOAD_CHECK='Both';
      NO_IO_CHECK='Both';
      NO_ASSERT_CHECK='TRUE';
      NO_DIR_CHECK='TRUE';
      ALLOW_CONNECT='TRUE';
    'VCCMPHY_1P05'<13>:
      PIN_NUMBER='(0,0,0,0,0,0,0,0,0,AE27,0,0,0,0)';
      PINUSE='POWER';
      NO_LOAD_CHECK='Both';
      NO_IO_CHECK='Both';
      NO_ASSERT_CHECK='TRUE';
      NO_DIR_CHECK='TRUE';
      ALLOW_CONNECT='TRUE';
    'VCCMPHY_1P05'<12>:
      PIN_NUMBER='(0,0,0,0,0,0,0,0,AK43,0,0,0,0,0)';
      PINUSE='POWER';
      NO_LOAD_CHECK='Both';
      NO_IO_CHECK='Both';
      NO_ASSERT_CHECK='TRUE';
      NO_DIR_CHECK='TRUE';
      ALLOW_CONNECT='TRUE';
    'VCCMPHY_1P05'<11>:
      PIN_NUMBER='(0,0,0,0,0,0,0,0,AK45,0,0,0,0,0)';
      PINUSE='POWER';
      NO_LOAD_CHECK='Both';
      NO_IO_CHECK='Both';
      NO_ASSERT_CHECK='TRUE';
      NO_DIR_CHECK='TRUE';
      ALLOW_CONNECT='TRUE';
    'VCCMPHY_1P05'<10>:
      PIN_NUMBER='(0,0,0,0,0,0,0,0,AM43,0,0,0,0,0)';
      PINUSE='POWER';
      NO_LOAD_CHECK='Both';
      NO_IO_CHECK='Both';
      NO_ASSERT_CHECK='TRUE';
      NO_DIR_CHECK='TRUE';
      ALLOW_CONNECT='TRUE';
    'VCCMPHY_1P05'<9>:
      PIN_NUMBER='(0,0,0,0,0,0,0,0,AM45,0,0,0,0,0)';
      PINUSE='POWER';
      NO_LOAD_CHECK='Both';
      NO_IO_CHECK='Both';
      NO_ASSERT_CHECK='TRUE';
      NO_DIR_CHECK='TRUE';
      ALLOW_CONNECT='TRUE';
    'VCCMPHY_1P05'<8>:
      PIN_NUMBER='(0,0,0,0,0,0,0,0,AP43,0,0,0,0,0)';
      PINUSE='POWER';
      NO_LOAD_CHECK='Both';
      NO_IO_CHECK='Both';
      NO_ASSERT_CHECK='TRUE';
      NO_DIR_CHECK='TRUE';
      ALLOW_CONNECT='TRUE';
    'VCCMPHY_1P05'<7>:
      PIN_NUMBER='(0,0,0,0,0,0,0,0,AP45,0,0,0,0,0)';
      PINUSE='POWER';
      NO_LOAD_CHECK='Both';
      NO_IO_CHECK='Both';
      NO_ASSERT_CHECK='TRUE';
      NO_DIR_CHECK='TRUE';
      ALLOW_CONNECT='TRUE';
    'VCCMPHY_1P05'<6>:
      PIN_NUMBER='(0,0,0,0,0,0,0,0,AT43,0,0,0,0,0)';
      PINUSE='POWER';
      NO_LOAD_CHECK='Both';
      NO_IO_CHECK='Both';
      NO_ASSERT_CHECK='TRUE';
      NO_DIR_CHECK='TRUE';
      ALLOW_CONNECT='TRUE';
    'VCCMPHY_1P05'<5>:
      PIN_NUMBER='(0,0,0,0,0,0,0,0,AT45,0,0,0,0,0)';
      PINUSE='POWER';
      NO_LOAD_CHECK='Both';
      NO_IO_CHECK='Both';
      NO_ASSERT_CHECK='TRUE';
      NO_DIR_CHECK='TRUE';
      ALLOW_CONNECT='TRUE';
    'VCCMPHY_1P05'<4>:
      PIN_NUMBER='(0,0,0,0,0,0,0,0,AU43,0,0,0,0,0)';
      PINUSE='POWER';
      NO_LOAD_CHECK='Both';
      NO_IO_CHECK='Both';
      NO_ASSERT_CHECK='TRUE';
      NO_DIR_CHECK='TRUE';
      ALLOW_CONNECT='TRUE';
    'VCCMPHY_1P05'<3>:
      PIN_NUMBER='(0,0,0,0,0,0,0,0,AU45,0,0,0,0,0)';
      PINUSE='POWER';
      NO_LOAD_CHECK='Both';
      NO_IO_CHECK='Both';
      NO_ASSERT_CHECK='TRUE';
      NO_DIR_CHECK='TRUE';
      ALLOW_CONNECT='TRUE';
    'VCCMPHY_1P05'<2>:
      PIN_NUMBER='(0,0,0,0,0,0,0,0,AJ43,0,0,0,0,0)';
      PINUSE='POWER';
      NO_LOAD_CHECK='Both';
      NO_IO_CHECK='Both';
      NO_ASSERT_CHECK='TRUE';
      NO_DIR_CHECK='TRUE';
      ALLOW_CONNECT='TRUE';
    'VCCMPHY_1P05'<1>:
      PIN_NUMBER='(0,0,0,0,0,0,0,0,AW43,0,0,0,0,0)';
      PINUSE='POWER';
      NO_LOAD_CHECK='Both';
      NO_IO_CHECK='Both';
      NO_ASSERT_CHECK='TRUE';
      NO_DIR_CHECK='TRUE';
      ALLOW_CONNECT='TRUE';
    'VCCMPHY_1P05'<0>:
      PIN_NUMBER='(0,0,0,0,0,0,0,0,AW45,0,0,0,0,0)';
      PINUSE='POWER';
      NO_LOAD_CHECK='Both';
      NO_IO_CHECK='Both';
      NO_ASSERT_CHECK='TRUE';
      NO_DIR_CHECK='TRUE';
      ALLOW_CONNECT='TRUE';
    'VCCP10GBEPLL_1P05'<3>:
      PIN_NUMBER='(0,0,0,0,0,0,0,0,BA39,0,0,0,0,0)';
      PINUSE='POWER';
      NO_LOAD_CHECK='Both';
      NO_IO_CHECK='Both';
      NO_ASSERT_CHECK='TRUE';
      NO_DIR_CHECK='TRUE';
      ALLOW_CONNECT='TRUE';
    'VCCP10GBEPLL_1P05'<2>:
      PIN_NUMBER='(0,0,0,0,0,0,0,0,BA41,0,0,0,0,0)';
      PINUSE='POWER';
      NO_LOAD_CHECK='Both';
      NO_IO_CHECK='Both';
      NO_ASSERT_CHECK='TRUE';
      NO_DIR_CHECK='TRUE';
      ALLOW_CONNECT='TRUE';
    'VCCP10GBEPLL_1P05'<1>:
      PIN_NUMBER='(0,0,0,0,0,0,0,0,BB40,0,0,0,0,0)';
      PINUSE='POWER';
      NO_LOAD_CHECK='Both';
      NO_IO_CHECK='Both';
      NO_ASSERT_CHECK='TRUE';
      NO_DIR_CHECK='TRUE';
      ALLOW_CONNECT='TRUE';
    'VCCP10GBEPLL_1P05'<0>:
      PIN_NUMBER='(0,0,0,0,0,0,0,0,BD38,0,0,0,0,0)';
      PINUSE='POWER';
      NO_LOAD_CHECK='Both';
      NO_IO_CHECK='Both';
      NO_ASSERT_CHECK='TRUE';
      NO_DIR_CHECK='TRUE';
      ALLOW_CONNECT='TRUE';
    'VCCP10GBE_HV_1P8'<1>:
      PIN_NUMBER='(0,0,0,0,0,0,0,0,BA27,0,0,0,0,0)';
      PINUSE='POWER';
      NO_LOAD_CHECK='Both';
      NO_IO_CHECK='Both';
      NO_ASSERT_CHECK='TRUE';
      NO_DIR_CHECK='TRUE';
      ALLOW_CONNECT='TRUE';
    'VCCP10GBE_HV_1P8'<0>:
      PIN_NUMBER='(0,0,0,0,0,0,0,0,BA29,0,0,0,0,0)';
      PINUSE='POWER';
      NO_LOAD_CHECK='Both';
      NO_IO_CHECK='Both';
      NO_ASSERT_CHECK='TRUE';
      NO_DIR_CHECK='TRUE';
      ALLOW_CONNECT='TRUE';
    'VCCP10GBE_LV_1P05'<6>:
      PIN_NUMBER='(0,0,0,0,0,0,0,0,BA30,0,0,0,0,0)';
      PINUSE='POWER';
      NO_LOAD_CHECK='Both';
      NO_IO_CHECK='Both';
      NO_ASSERT_CHECK='TRUE';
      NO_DIR_CHECK='TRUE';
      ALLOW_CONNECT='TRUE';
    'VCCP10GBE_LV_1P05'<5>:
      PIN_NUMBER='(0,0,0,0,0,0,0,0,BA32,0,0,0,0,0)';
      PINUSE='POWER';
      NO_LOAD_CHECK='Both';
      NO_IO_CHECK='Both';
      NO_ASSERT_CHECK='TRUE';
      NO_DIR_CHECK='TRUE';
      ALLOW_CONNECT='TRUE';
    'VCCP10GBE_LV_1P05'<4>:
      PIN_NUMBER='(0,0,0,0,0,0,0,0,BA34,0,0,0,0,0)';
      PINUSE='POWER';
      NO_LOAD_CHECK='Both';
      NO_IO_CHECK='Both';
      NO_ASSERT_CHECK='TRUE';
      NO_DIR_CHECK='TRUE';
      ALLOW_CONNECT='TRUE';
    'VCCP10GBE_LV_1P05'<3>:
      PIN_NUMBER='(0,0,0,0,0,0,0,0,BA36,0,0,0,0,0)';
      PINUSE='POWER';
      NO_LOAD_CHECK='Both';
      NO_IO_CHECK='Both';
      NO_ASSERT_CHECK='TRUE';
      NO_DIR_CHECK='TRUE';
      ALLOW_CONNECT='TRUE';
    'VCCP10GBE_LV_1P05'<2>:
      PIN_NUMBER='(0,0,0,0,0,0,0,0,BA37,0,0,0,0,0)';
      PINUSE='POWER';
      NO_LOAD_CHECK='Both';
      NO_IO_CHECK='Both';
      NO_ASSERT_CHECK='TRUE';
      NO_DIR_CHECK='TRUE';
      ALLOW_CONNECT='TRUE';
    'VCCP10GBE_LV_1P05'<1>:
      PIN_NUMBER='(0,0,0,0,0,0,0,0,BB33,0,0,0,0,0)';
      PINUSE='POWER';
      NO_LOAD_CHECK='Both';
      NO_IO_CHECK='Both';
      NO_ASSERT_CHECK='TRUE';
      NO_DIR_CHECK='TRUE';
      ALLOW_CONNECT='TRUE';
    'VCCP10GBE_LV_1P05'<0>:
      PIN_NUMBER='(0,0,0,0,0,0,0,0,BB37,0,0,0,0,0)';
      PINUSE='POWER';
      NO_LOAD_CHECK='Both';
      NO_IO_CHECK='Both';
      NO_ASSERT_CHECK='TRUE';
      NO_DIR_CHECK='TRUE';
      ALLOW_CONNECT='TRUE';
    'VCCPDSW_3P3':
      PIN_NUMBER='(0,0,0,0,0,0,0,0,AH24,0,0,0,0,0)';
      PINUSE='POWER';
      NO_LOAD_CHECK='Both';
      NO_IO_CHECK='Both';
      NO_ASSERT_CHECK='TRUE';
      NO_DIR_CHECK='TRUE';
      ALLOW_CONNECT='TRUE';
    'VCCPGPPA':
      PIN_NUMBER='(0,0,0,0,0,0,0,0,AW24,0,0,0,0,0)';
      PINUSE='POWER';
      NO_LOAD_CHECK='Both';
      NO_IO_CHECK='Both';
      NO_ASSERT_CHECK='TRUE';
      NO_DIR_CHECK='TRUE';
      ALLOW_CONNECT='TRUE';
    'VCCPGPPB':
      PIN_NUMBER='(0,0,0,0,0,0,0,0,BE26,0,0,0,0,0)';
      PINUSE='POWER';
      NO_LOAD_CHECK='Both';
      NO_IO_CHECK='Both';
      NO_ASSERT_CHECK='TRUE';
      NO_DIR_CHECK='TRUE';
      ALLOW_CONNECT='TRUE';
    'VCCPGPPC':
      PIN_NUMBER='(0,0,0,0,0,0,0,0,BE40,0,0,0,0,0)';
      PINUSE='POWER';
      NO_LOAD_CHECK='Both';
      NO_IO_CHECK='Both';
      NO_ASSERT_CHECK='TRUE';
      NO_DIR_CHECK='TRUE';
      ALLOW_CONNECT='TRUE';
    'VCCPGPPD':
      PIN_NUMBER='(0,0,0,0,0,0,0,0,BA43,0,0,0,0,0)';
      PINUSE='POWER';
      NO_LOAD_CHECK='Both';
      NO_IO_CHECK='Both';
      NO_ASSERT_CHECK='TRUE';
      NO_DIR_CHECK='TRUE';
      ALLOW_CONNECT='TRUE';
    'VCCPGPPE':
      PIN_NUMBER='(0,0,0,0,0,0,0,0,BE44,0,0,0,0,0)';
      PINUSE='POWER';
      NO_LOAD_CHECK='Both';
      NO_IO_CHECK='Both';
      NO_ASSERT_CHECK='TRUE';
      NO_DIR_CHECK='TRUE';
      ALLOW_CONNECT='TRUE';
    'VCCPGPPF':
      PIN_NUMBER='(0,0,0,0,0,0,0,0,AU27,0,0,0,0,0)';
      PINUSE='POWER';
      NO_LOAD_CHECK='Both';
      NO_IO_CHECK='Both';
      NO_ASSERT_CHECK='TRUE';
      NO_DIR_CHECK='TRUE';
      ALLOW_CONNECT='TRUE';
    'VCCPGPPG':
      PIN_NUMBER='(0,0,0,0,0,0,0,0,BA26,0,0,0,0,0)';
      PINUSE='POWER';
      NO_LOAD_CHECK='Both';
      NO_IO_CHECK='Both';
      NO_ASSERT_CHECK='TRUE';
      NO_DIR_CHECK='TRUE';
      ALLOW_CONNECT='TRUE';
    'VCCPGPPH':
      PIN_NUMBER='(0,0,0,0,0,0,0,0,BA24,0,0,0,0,0)';
      PINUSE='POWER';
      NO_LOAD_CHECK='Both';
      NO_IO_CHECK='Both';
      NO_ASSERT_CHECK='TRUE';
      NO_DIR_CHECK='TRUE';
      ALLOW_CONNECT='TRUE';
    'VCCPGPPJ':
      PIN_NUMBER='(0,0,0,0,0,0,0,0,BB26,0,0,0,0,0)';
      PINUSE='POWER';
      NO_LOAD_CHECK='Both';
      NO_IO_CHECK='Both';
      NO_ASSERT_CHECK='TRUE';
      NO_DIR_CHECK='TRUE';
      ALLOW_CONNECT='TRUE';
    'VCCPGPPK':
      PIN_NUMBER='(0,0,0,0,0,0,0,0,AU24,0,0,0,0,0)';
      PINUSE='POWER';
      NO_LOAD_CHECK='Both';
      NO_IO_CHECK='Both';
      NO_ASSERT_CHECK='TRUE';
      NO_DIR_CHECK='TRUE';
      ALLOW_CONNECT='TRUE';
    'VCCPGPP_1P8'<6>:
      PIN_NUMBER='(0,0,0,0,0,0,0,0,AK24,0,0,0,0,0)';
      PINUSE='POWER';
      NO_LOAD_CHECK='Both';
      NO_IO_CHECK='Both';
      NO_ASSERT_CHECK='TRUE';
      NO_DIR_CHECK='TRUE';
      ALLOW_CONNECT='TRUE';
    'VCCPGPP_1P8'<5>:
      PIN_NUMBER='(0,0,0,0,0,0,0,0,AW27,0,0,0,0,0)';
      PINUSE='POWER';
      NO_LOAD_CHECK='Both';
      NO_IO_CHECK='Both';
      NO_ASSERT_CHECK='TRUE';
      NO_DIR_CHECK='TRUE';
      ALLOW_CONNECT='TRUE';
    'VCCPGPP_1P8'<4>:
      PIN_NUMBER='(0,0,0,0,0,0,0,0,AP29,0,0,0,0,0)';
      PINUSE='POWER';
      NO_LOAD_CHECK='Both';
      NO_IO_CHECK='Both';
      NO_ASSERT_CHECK='TRUE';
      NO_DIR_CHECK='TRUE';
      ALLOW_CONNECT='TRUE';
    'VCCPGPP_1P8'<3>:
      PIN_NUMBER='(0,0,0,0,0,0,0,0,AM29,0,0,0,0,0)';
      PINUSE='POWER';
      NO_LOAD_CHECK='Both';
      NO_IO_CHECK='Both';
      NO_ASSERT_CHECK='TRUE';
      NO_DIR_CHECK='TRUE';
      ALLOW_CONNECT='TRUE';
    'VCCPGPP_1P8'<2>:
      PIN_NUMBER='(0,0,0,0,0,0,0,0,AT29,0,0,0,0,0)';
      PINUSE='POWER';
      NO_LOAD_CHECK='Both';
      NO_IO_CHECK='Both';
      NO_ASSERT_CHECK='TRUE';
      NO_DIR_CHECK='TRUE';
      ALLOW_CONNECT='TRUE';
    'VCCPGPP_1P8'<1>:
      PIN_NUMBER='(0,0,0,0,0,0,0,0,AW29,0,0,0,0,0)';
      PINUSE='POWER';
      NO_LOAD_CHECK='Both';
      NO_IO_CHECK='Both';
      NO_ASSERT_CHECK='TRUE';
      NO_DIR_CHECK='TRUE';
      ALLOW_CONNECT='TRUE';
    'VCCPGPP_1P8'<0>:
      PIN_NUMBER='(0,0,0,0,0,0,0,0,AU29,0,0,0,0,0)';
      PINUSE='POWER';
      NO_LOAD_CHECK='Both';
      NO_IO_CHECK='Both';
      NO_ASSERT_CHECK='TRUE';
      NO_DIR_CHECK='TRUE';
      ALLOW_CONNECT='TRUE';
    'VCCPHDA_1P8':
      PIN_NUMBER='(0,0,0,0,0,0,0,0,AG27,0,0,0,0,0)';
      PINUSE='POWER';
      NO_LOAD_CHECK='Both';
      NO_IO_CHECK='Both';
      NO_ASSERT_CHECK='TRUE';
      NO_DIR_CHECK='TRUE';
      ALLOW_CONNECT='TRUE';
    'VCCPRIM_1P05'<19>:
      PIN_NUMBER='(0,0,0,0,0,0,0,0,Y26,0,0,0,0,0)';
      PINUSE='POWER';
      NO_LOAD_CHECK='Both';
      NO_IO_CHECK='Both';
      NO_ASSERT_CHECK='TRUE';
      NO_DIR_CHECK='TRUE';
      ALLOW_CONNECT='TRUE';
    'VCCPRIM_1P05'<18>:
      PIN_NUMBER='(0,0,0,0,0,0,0,0,AA24,0,0,0,0,0)';
      PINUSE='POWER';
      NO_LOAD_CHECK='Both';
      NO_IO_CHECK='Both';
      NO_ASSERT_CHECK='TRUE';
      NO_DIR_CHECK='TRUE';
      ALLOW_CONNECT='TRUE';
    'VCCPRIM_1P05'<17>:
      PIN_NUMBER='(0,0,0,0,0,0,0,0,AK27,0,0,0,0,0)';
      PINUSE='UNSPEC';
      NO_LOAD_CHECK='Both';
      NO_IO_CHECK='Both';
      NO_ASSERT_CHECK='TRUE';
      NO_DIR_CHECK='TRUE';
      ALLOW_CONNECT='TRUE';
    'VCCPRIM_1P05'<16>:
      PIN_NUMBER='(0,0,0,0,0,0,0,0,R42,0,0,0,0,0)';
      PINUSE='POWER';
      NO_LOAD_CHECK='Both';
      NO_IO_CHECK='Both';
      NO_ASSERT_CHECK='TRUE';
      NO_DIR_CHECK='TRUE';
      ALLOW_CONNECT='TRUE';
    'VCCPRIM_1P05'<15>:
      PIN_NUMBER='(0,0,0,0,0,0,0,0,R46,0,0,0,0,0)';
      PINUSE='POWER';
      NO_LOAD_CHECK='Both';
      NO_IO_CHECK='Both';
      NO_ASSERT_CHECK='TRUE';
      NO_DIR_CHECK='TRUE';
      ALLOW_CONNECT='TRUE';
    'VCCPRIM_1P05'<14>:
      PIN_NUMBER='(0,0,0,0,0,0,0,0,T44,0,0,0,0,0)';
      PINUSE='POWER';
      NO_LOAD_CHECK='Both';
      NO_IO_CHECK='Both';
      NO_ASSERT_CHECK='TRUE';
      NO_DIR_CHECK='TRUE';
      ALLOW_CONNECT='TRUE';
    'VCCPRIM_1P05'<13>:
      PIN_NUMBER='(0,0,0,0,0,0,0,0,U46,0,0,0,0,0)';
      PINUSE='POWER';
      NO_LOAD_CHECK='Both';
      NO_IO_CHECK='Both';
      NO_ASSERT_CHECK='TRUE';
      NO_DIR_CHECK='TRUE';
      ALLOW_CONNECT='TRUE';
    'VCCPRIM_1P05'<12>:
      PIN_NUMBER='(0,0,0,0,0,0,0,0,V44,0,0,0,0,0)';
      PINUSE='POWER';
      NO_LOAD_CHECK='Both';
      NO_IO_CHECK='Both';
      NO_ASSERT_CHECK='TRUE';
      NO_DIR_CHECK='TRUE';
      ALLOW_CONNECT='TRUE';
    'VCCPRIM_1P05'<11>:
      PIN_NUMBER='(0,0,0,0,0,0,0,0,Y45,0,0,0,0,0)';
      PINUSE='POWER';
      NO_LOAD_CHECK='Both';
      NO_IO_CHECK='Both';
      NO_ASSERT_CHECK='TRUE';
      NO_DIR_CHECK='TRUE';
      ALLOW_CONNECT='TRUE';
    'VCCPRIM_1P05'<10>:
      PIN_NUMBER='(0,0,0,0,0,0,0,0,Y46,0,0,0,0,0)';
      PINUSE='POWER';
      NO_LOAD_CHECK='Both';
      NO_IO_CHECK='Both';
      NO_ASSERT_CHECK='TRUE';
      NO_DIR_CHECK='TRUE';
      ALLOW_CONNECT='TRUE';
    'VCCPRIM_1P05'<9>:
      PIN_NUMBER='(0,0,0,0,0,0,0,0,AA45,0,0,0,0,0)';
      PINUSE='POWER';
      NO_LOAD_CHECK='Both';
      NO_IO_CHECK='Both';
      NO_ASSERT_CHECK='TRUE';
      NO_DIR_CHECK='TRUE';
      ALLOW_CONNECT='TRUE';
    'VCCPRIM_1P05'<8>:
      PIN_NUMBER='(0,0,0,0,0,0,0,0,AA46,0,0,0,0,0)';
      PINUSE='POWER';
      NO_LOAD_CHECK='Both';
      NO_IO_CHECK='Both';
      NO_ASSERT_CHECK='TRUE';
      NO_DIR_CHECK='TRUE';
      ALLOW_CONNECT='TRUE';
    'VCCPRIM_1P05'<7>:
      PIN_NUMBER='(0,0,0,0,0,0,0,0,AC26,0,0,0,0,0)';
      PINUSE='POWER';
      NO_LOAD_CHECK='Both';
      NO_IO_CHECK='Both';
      NO_ASSERT_CHECK='TRUE';
      NO_DIR_CHECK='TRUE';
      ALLOW_CONNECT='TRUE';
    'VCCPRIM_1P05'<6>:
      PIN_NUMBER='(0,0,0,0,0,0,0,0,AJ29,0,0,0,0,0)';
      PINUSE='POWER';
      NO_LOAD_CHECK='Both';
      NO_IO_CHECK='Both';
      NO_ASSERT_CHECK='TRUE';
      NO_DIR_CHECK='TRUE';
      ALLOW_CONNECT='TRUE';
    'VCCPRIM_1P05'<5>:
      PIN_NUMBER='(0,0,0,0,0,0,0,0,AM27,0,0,0,0,0)';
      PINUSE='POWER';
      NO_LOAD_CHECK='Both';
      NO_IO_CHECK='Both';
      NO_ASSERT_CHECK='TRUE';
      NO_DIR_CHECK='TRUE';
      ALLOW_CONNECT='TRUE';
    'VCCPRIM_1P05'<4>:
      PIN_NUMBER='(0,0,0,0,0,0,0,0,AT39,0,0,0,0,0)';
      PINUSE='POWER';
      NO_LOAD_CHECK='Both';
      NO_IO_CHECK='Both';
      NO_ASSERT_CHECK='TRUE';
      NO_DIR_CHECK='TRUE';
      ALLOW_CONNECT='TRUE';
    'VCCPRIM_1P05'<3>:
      PIN_NUMBER='(0,0,0,0,0,0,0,0,AU37,0,0,0,0,0)';
      PINUSE='POWER';
      NO_LOAD_CHECK='Both';
      NO_IO_CHECK='Both';
      NO_ASSERT_CHECK='TRUE';
      NO_DIR_CHECK='TRUE';
      ALLOW_CONNECT='TRUE';
    'VCCPRIM_1P05'<2>:
      PIN_NUMBER='(0,0,0,0,0,0,0,0,AU39,0,0,0,0,0)';
      PINUSE='POWER';
      NO_LOAD_CHECK='Both';
      NO_IO_CHECK='Both';
      NO_ASSERT_CHECK='TRUE';
      NO_DIR_CHECK='TRUE';
      ALLOW_CONNECT='TRUE';
    'VCCPRIM_1P05'<1>:
      PIN_NUMBER='(0,0,0,0,0,0,0,0,BE48,0,0,0,0,0)';
      PINUSE='POWER';
      NO_LOAD_CHECK='Both';
      NO_IO_CHECK='Both';
      NO_ASSERT_CHECK='TRUE';
      NO_DIR_CHECK='TRUE';
      ALLOW_CONNECT='TRUE';
    'VCCPRIM_1P05'<0>:
      PIN_NUMBER='(0,0,0,0,0,0,0,0,BF46,0,0,0,0,0)';
      PINUSE='POWER';
      NO_LOAD_CHECK='Both';
      NO_IO_CHECK='Both';
      NO_ASSERT_CHECK='TRUE';
      NO_DIR_CHECK='TRUE';
      ALLOW_CONNECT='TRUE';
    'VCCPRIM_AVID'<62>:
      PIN_NUMBER='(0,0,0,0,0,0,0,0,0,AK32,0,0,0,0)';
      PINUSE='UNSPEC';
      NO_LOAD_CHECK='Both';
      NO_IO_CHECK='Both';
      NO_ASSERT_CHECK='TRUE';
      NO_DIR_CHECK='TRUE';
      ALLOW_CONNECT='TRUE';
    'VCCPRIM_AVID'<61>:
      PIN_NUMBER='(0,0,0,0,0,0,0,0,0,U31,0,0,0,0)';
      PINUSE='POWER';
      NO_LOAD_CHECK='Both';
      NO_IO_CHECK='Both';
      NO_ASSERT_CHECK='TRUE';
      NO_DIR_CHECK='TRUE';
      ALLOW_CONNECT='TRUE';
    'VCCPRIM_AVID'<60>:
      PIN_NUMBER='(0,0,0,0,0,0,0,0,0,U35,0,0,0,0)';
      PINUSE='POWER';
      NO_LOAD_CHECK='Both';
      NO_IO_CHECK='Both';
      NO_ASSERT_CHECK='TRUE';
      NO_DIR_CHECK='TRUE';
      ALLOW_CONNECT='TRUE';
    'VCCPRIM_AVID'<59>:
      PIN_NUMBER='(0,0,0,0,0,0,0,0,0,U38,0,0,0,0)';
      PINUSE='POWER';
      NO_LOAD_CHECK='Both';
      NO_IO_CHECK='Both';
      NO_ASSERT_CHECK='TRUE';
      NO_DIR_CHECK='TRUE';
      ALLOW_CONNECT='TRUE';
    'VCCPRIM_AVID'<58>:
      PIN_NUMBER='(0,0,0,0,0,0,0,0,0,V29,0,0,0,0)';
      PINUSE='POWER';
      NO_LOAD_CHECK='Both';
      NO_IO_CHECK='Both';
      NO_ASSERT_CHECK='TRUE';
      NO_DIR_CHECK='TRUE';
      ALLOW_CONNECT='TRUE';
    'VCCPRIM_AVID'<57>:
      PIN_NUMBER='(0,0,0,0,0,0,0,0,0,V33,0,0,0,0)';
      PINUSE='POWER';
      NO_LOAD_CHECK='Both';
      NO_IO_CHECK='Both';
      NO_ASSERT_CHECK='TRUE';
      NO_DIR_CHECK='TRUE';
      ALLOW_CONNECT='TRUE';
    'VCCPRIM_AVID'<56>:
      PIN_NUMBER='(0,0,0,0,0,0,0,0,0,V40,0,0,0,0)';
      PINUSE='POWER';
      NO_LOAD_CHECK='Both';
      NO_IO_CHECK='Both';
      NO_ASSERT_CHECK='TRUE';
      NO_DIR_CHECK='TRUE';
      ALLOW_CONNECT='TRUE';
    'VCCPRIM_AVID'<55>:
      PIN_NUMBER='(0,0,0,0,0,0,0,0,0,Y29,0,0,0,0)';
      PINUSE='POWER';
      NO_LOAD_CHECK='Both';
      NO_IO_CHECK='Both';
      NO_ASSERT_CHECK='TRUE';
      NO_DIR_CHECK='TRUE';
      ALLOW_CONNECT='TRUE';
    'VCCPRIM_AVID'<54>:
      PIN_NUMBER='(0,0,0,0,0,0,0,0,0,Y30,0,0,0,0)';
      PINUSE='POWER';
      NO_LOAD_CHECK='Both';
      NO_IO_CHECK='Both';
      NO_ASSERT_CHECK='TRUE';
      NO_DIR_CHECK='TRUE';
      ALLOW_CONNECT='TRUE';
    'VCCPRIM_AVID'<53>:
      PIN_NUMBER='(0,0,0,0,0,0,0,0,0,Y32,0,0,0,0)';
      PINUSE='POWER';
      NO_LOAD_CHECK='Both';
      NO_IO_CHECK='Both';
      NO_ASSERT_CHECK='TRUE';
      NO_DIR_CHECK='TRUE';
      ALLOW_CONNECT='TRUE';
    'VCCPRIM_AVID'<52>:
      PIN_NUMBER='(0,0,0,0,0,0,0,0,0,Y34,0,0,0,0)';
      PINUSE='POWER';
      NO_LOAD_CHECK='Both';
      NO_IO_CHECK='Both';
      NO_ASSERT_CHECK='TRUE';
      NO_DIR_CHECK='TRUE';
      ALLOW_CONNECT='TRUE';
    'VCCPRIM_AVID'<51>:
      PIN_NUMBER='(0,0,0,0,0,0,0,0,0,Y36,0,0,0,0)';
      PINUSE='POWER';
      NO_LOAD_CHECK='Both';
      NO_IO_CHECK='Both';
      NO_ASSERT_CHECK='TRUE';
      NO_DIR_CHECK='TRUE';
      ALLOW_CONNECT='TRUE';
    'VCCPRIM_AVID'<50>:
      PIN_NUMBER='(0,0,0,0,0,0,0,0,0,Y37,0,0,0,0)';
      PINUSE='POWER';
      NO_LOAD_CHECK='Both';
      NO_IO_CHECK='Both';
      NO_ASSERT_CHECK='TRUE';
      NO_DIR_CHECK='TRUE';
      ALLOW_CONNECT='TRUE';
    'VCCPRIM_AVID'<49>:
      PIN_NUMBER='(0,0,0,0,0,0,0,0,0,Y39,0,0,0,0)';
      PINUSE='POWER';
      NO_LOAD_CHECK='Both';
      NO_IO_CHECK='Both';
      NO_ASSERT_CHECK='TRUE';
      NO_DIR_CHECK='TRUE';
      ALLOW_CONNECT='TRUE';
    'VCCPRIM_AVID'<48>:
      PIN_NUMBER='(0,0,0,0,0,0,0,0,0,Y41,0,0,0,0)';
      PINUSE='POWER';
      NO_LOAD_CHECK='Both';
      NO_IO_CHECK='Both';
      NO_ASSERT_CHECK='TRUE';
      NO_DIR_CHECK='TRUE';
      ALLOW_CONNECT='TRUE';
    'VCCPRIM_AVID'<47>:
      PIN_NUMBER='(0,0,0,0,0,0,0,0,0,AA29,0,0,0,0)';
      PINUSE='POWER';
      NO_LOAD_CHECK='Both';
      NO_IO_CHECK='Both';
      NO_ASSERT_CHECK='TRUE';
      NO_DIR_CHECK='TRUE';
      ALLOW_CONNECT='TRUE';
    'VCCPRIM_AVID'<46>:
      PIN_NUMBER='(0,0,0,0,0,0,0,0,0,AA30,0,0,0,0)';
      PINUSE='POWER';
      NO_LOAD_CHECK='Both';
      NO_IO_CHECK='Both';
      NO_ASSERT_CHECK='TRUE';
      NO_DIR_CHECK='TRUE';
      ALLOW_CONNECT='TRUE';
    'VCCPRIM_AVID'<45>:
      PIN_NUMBER='(0,0,0,0,0,0,0,0,0,AA32,0,0,0,0)';
      PINUSE='POWER';
      NO_LOAD_CHECK='Both';
      NO_IO_CHECK='Both';
      NO_ASSERT_CHECK='TRUE';
      NO_DIR_CHECK='TRUE';
      ALLOW_CONNECT='TRUE';
    'VCCPRIM_AVID'<44>:
      PIN_NUMBER='(0,0,0,0,0,0,0,0,0,AA34,0,0,0,0)';
      PINUSE='POWER';
      NO_LOAD_CHECK='Both';
      NO_IO_CHECK='Both';
      NO_ASSERT_CHECK='TRUE';
      NO_DIR_CHECK='TRUE';
      ALLOW_CONNECT='TRUE';
    'VCCPRIM_AVID'<43>:
      PIN_NUMBER='(0,0,0,0,0,0,0,0,0,AA36,0,0,0,0)';
      PINUSE='POWER';
      NO_LOAD_CHECK='Both';
      NO_IO_CHECK='Both';
      NO_ASSERT_CHECK='TRUE';
      NO_DIR_CHECK='TRUE';
      ALLOW_CONNECT='TRUE';
    'VCCPRIM_AVID'<42>:
      PIN_NUMBER='(0,0,0,0,0,0,0,0,0,AA37,0,0,0,0)';
      PINUSE='POWER';
      NO_LOAD_CHECK='Both';
      NO_IO_CHECK='Both';
      NO_ASSERT_CHECK='TRUE';
      NO_DIR_CHECK='TRUE';
      ALLOW_CONNECT='TRUE';
    'VCCPRIM_AVID'<41>:
      PIN_NUMBER='(0,0,0,0,0,0,0,0,0,AA39,0,0,0,0)';
      PINUSE='POWER';
      NO_LOAD_CHECK='Both';
      NO_IO_CHECK='Both';
      NO_ASSERT_CHECK='TRUE';
      NO_DIR_CHECK='TRUE';
      ALLOW_CONNECT='TRUE';
    'VCCPRIM_AVID'<40>:
      PIN_NUMBER='(0,0,0,0,0,0,0,0,0,AA41,0,0,0,0)';
      PINUSE='POWER';
      NO_LOAD_CHECK='Both';
      NO_IO_CHECK='Both';
      NO_ASSERT_CHECK='TRUE';
      NO_DIR_CHECK='TRUE';
      ALLOW_CONNECT='TRUE';
    'VCCPRIM_AVID'<39>:
      PIN_NUMBER='(0,0,0,0,0,0,0,0,0,AC29,0,0,0,0)';
      PINUSE='POWER';
      NO_LOAD_CHECK='Both';
      NO_IO_CHECK='Both';
      NO_ASSERT_CHECK='TRUE';
      NO_DIR_CHECK='TRUE';
      ALLOW_CONNECT='TRUE';
    'VCCPRIM_AVID'<38>:
      PIN_NUMBER='(0,0,0,0,0,0,0,0,0,AC30,0,0,0,0)';
      PINUSE='POWER';
      NO_LOAD_CHECK='Both';
      NO_IO_CHECK='Both';
      NO_ASSERT_CHECK='TRUE';
      NO_DIR_CHECK='TRUE';
      ALLOW_CONNECT='TRUE';
    'VCCPRIM_AVID'<37>:
      PIN_NUMBER='(0,0,0,0,0,0,0,0,0,AC32,0,0,0,0)';
      PINUSE='POWER';
      NO_LOAD_CHECK='Both';
      NO_IO_CHECK='Both';
      NO_ASSERT_CHECK='TRUE';
      NO_DIR_CHECK='TRUE';
      ALLOW_CONNECT='TRUE';
    'VCCPRIM_AVID'<36>:
      PIN_NUMBER='(0,0,0,0,0,0,0,0,0,AC34,0,0,0,0)';
      PINUSE='POWER';
      NO_LOAD_CHECK='Both';
      NO_IO_CHECK='Both';
      NO_ASSERT_CHECK='TRUE';
      NO_DIR_CHECK='TRUE';
      ALLOW_CONNECT='TRUE';
    'VCCPRIM_AVID'<35>:
      PIN_NUMBER='(0,0,0,0,0,0,0,0,0,AC36,0,0,0,0)';
      PINUSE='POWER';
      NO_LOAD_CHECK='Both';
      NO_IO_CHECK='Both';
      NO_ASSERT_CHECK='TRUE';
      NO_DIR_CHECK='TRUE';
      ALLOW_CONNECT='TRUE';
    'VCCPRIM_AVID'<34>:
      PIN_NUMBER='(0,0,0,0,0,0,0,0,0,AC37,0,0,0,0)';
      PINUSE='POWER';
      NO_LOAD_CHECK='Both';
      NO_IO_CHECK='Both';
      NO_ASSERT_CHECK='TRUE';
      NO_DIR_CHECK='TRUE';
      ALLOW_CONNECT='TRUE';
    'VCCPRIM_AVID'<33>:
      PIN_NUMBER='(0,0,0,0,0,0,0,0,0,AC39,0,0,0,0)';
      PINUSE='POWER';
      NO_LOAD_CHECK='Both';
      NO_IO_CHECK='Both';
      NO_ASSERT_CHECK='TRUE';
      NO_DIR_CHECK='TRUE';
      ALLOW_CONNECT='TRUE';
    'VCCPRIM_AVID'<32>:
      PIN_NUMBER='(0,0,0,0,0,0,0,0,0,AC41,0,0,0,0)';
      PINUSE='POWER';
      NO_LOAD_CHECK='Both';
      NO_IO_CHECK='Both';
      NO_ASSERT_CHECK='TRUE';
      NO_DIR_CHECK='TRUE';
      ALLOW_CONNECT='TRUE';
    'VCCPRIM_AVID'<31>:
      PIN_NUMBER='(0,0,0,0,0,0,0,0,0,U27,0,0,0,0)';
      PINUSE='UNSPEC';
      NO_LOAD_CHECK='Both';
      NO_IO_CHECK='Both';
      NO_ASSERT_CHECK='TRUE';
      NO_DIR_CHECK='TRUE';
      ALLOW_CONNECT='TRUE';
    'VCCPRIM_AVID'<30>:
      PIN_NUMBER='(0,0,0,0,0,0,0,0,0,AE30,0,0,0,0)';
      PINUSE='POWER';
      NO_LOAD_CHECK='Both';
      NO_IO_CHECK='Both';
      NO_ASSERT_CHECK='TRUE';
      NO_DIR_CHECK='TRUE';
      ALLOW_CONNECT='TRUE';
    'VCCPRIM_AVID'<29>:
      PIN_NUMBER='(0,0,0,0,0,0,0,0,0,AE32,0,0,0,0)';
      PINUSE='POWER';
      NO_LOAD_CHECK='Both';
      NO_IO_CHECK='Both';
      NO_ASSERT_CHECK='TRUE';
      NO_DIR_CHECK='TRUE';
      ALLOW_CONNECT='TRUE';
    'VCCPRIM_AVID'<28>:
      PIN_NUMBER='(0,0,0,0,0,0,0,0,0,AE34,0,0,0,0)';
      PINUSE='POWER';
      NO_LOAD_CHECK='Both';
      NO_IO_CHECK='Both';
      NO_ASSERT_CHECK='TRUE';
      NO_DIR_CHECK='TRUE';
      ALLOW_CONNECT='TRUE';
    'VCCPRIM_AVID'<27>:
      PIN_NUMBER='(0,0,0,0,0,0,0,0,0,AE36,0,0,0,0)';
      PINUSE='POWER';
      NO_LOAD_CHECK='Both';
      NO_IO_CHECK='Both';
      NO_ASSERT_CHECK='TRUE';
      NO_DIR_CHECK='TRUE';
      ALLOW_CONNECT='TRUE';
    'VCCPRIM_AVID'<26>:
      PIN_NUMBER='(0,0,0,0,0,0,0,0,0,AE37,0,0,0,0)';
      PINUSE='POWER';
      NO_LOAD_CHECK='Both';
      NO_IO_CHECK='Both';
      NO_ASSERT_CHECK='TRUE';
      NO_DIR_CHECK='TRUE';
      ALLOW_CONNECT='TRUE';
    'VCCPRIM_AVID'<25>:
      PIN_NUMBER='(0,0,0,0,0,0,0,0,0,AE39,0,0,0,0)';
      PINUSE='POWER';
      NO_LOAD_CHECK='Both';
      NO_IO_CHECK='Both';
      NO_ASSERT_CHECK='TRUE';
      NO_DIR_CHECK='TRUE';
      ALLOW_CONNECT='TRUE';
    'VCCPRIM_AVID'<24>:
      PIN_NUMBER='(0,0,0,0,0,0,0,0,0,AE41,0,0,0,0)';
      PINUSE='POWER';
      NO_LOAD_CHECK='Both';
      NO_IO_CHECK='Both';
      NO_ASSERT_CHECK='TRUE';
      NO_DIR_CHECK='TRUE';
      ALLOW_CONNECT='TRUE';
    'VCCPRIM_AVID'<23>:
      PIN_NUMBER='(0,0,0,0,0,0,0,0,0,AG32,0,0,0,0)';
      PINUSE='POWER';
      NO_LOAD_CHECK='Both';
      NO_IO_CHECK='Both';
      NO_ASSERT_CHECK='TRUE';
      NO_DIR_CHECK='TRUE';
      ALLOW_CONNECT='TRUE';
    'VCCPRIM_AVID'<22>:
      PIN_NUMBER='(0,0,0,0,0,0,0,0,0,AG34,0,0,0,0)';
      PINUSE='POWER';
      NO_LOAD_CHECK='Both';
      NO_IO_CHECK='Both';
      NO_ASSERT_CHECK='TRUE';
      NO_DIR_CHECK='TRUE';
      ALLOW_CONNECT='TRUE';
    'VCCPRIM_AVID'<21>:
      PIN_NUMBER='(0,0,0,0,0,0,0,0,0,AG36,0,0,0,0)';
      PINUSE='POWER';
      NO_LOAD_CHECK='Both';
      NO_IO_CHECK='Both';
      NO_ASSERT_CHECK='TRUE';
      NO_DIR_CHECK='TRUE';
      ALLOW_CONNECT='TRUE';
    'VCCPRIM_AVID'<20>:
      PIN_NUMBER='(0,0,0,0,0,0,0,0,0,AG37,0,0,0,0)';
      PINUSE='POWER';
      NO_LOAD_CHECK='Both';
      NO_IO_CHECK='Both';
      NO_ASSERT_CHECK='TRUE';
      NO_DIR_CHECK='TRUE';
      ALLOW_CONNECT='TRUE';
    'VCCPRIM_AVID'<19>:
      PIN_NUMBER='(0,0,0,0,0,0,0,0,0,AG39,0,0,0,0)';
      PINUSE='POWER';
      NO_LOAD_CHECK='Both';
      NO_IO_CHECK='Both';
      NO_ASSERT_CHECK='TRUE';
      NO_DIR_CHECK='TRUE';
      ALLOW_CONNECT='TRUE';
    'VCCPRIM_AVID'<18>:
      PIN_NUMBER='(0,0,0,0,0,0,0,0,0,AK34,0,0,0,0)';
      PINUSE='POWER';
      NO_LOAD_CHECK='Both';
      NO_IO_CHECK='Both';
      NO_ASSERT_CHECK='TRUE';
      NO_DIR_CHECK='TRUE';
      ALLOW_CONNECT='TRUE';
    'VCCPRIM_AVID'<17>:
      PIN_NUMBER='(0,0,0,0,0,0,0,0,0,AK37,0,0,0,0)';
      PINUSE='POWER';
      NO_LOAD_CHECK='Both';
      NO_IO_CHECK='Both';
      NO_ASSERT_CHECK='TRUE';
      NO_DIR_CHECK='TRUE';
      ALLOW_CONNECT='TRUE';
    'VCCPRIM_AVID'<16>:
      PIN_NUMBER='(0,0,0,0,0,0,0,0,0,AK39,0,0,0,0)';
      PINUSE='POWER';
      NO_LOAD_CHECK='Both';
      NO_IO_CHECK='Both';
      NO_ASSERT_CHECK='TRUE';
      NO_DIR_CHECK='TRUE';
      ALLOW_CONNECT='TRUE';
    'VCCPRIM_AVID'<15>:
      PIN_NUMBER='(0,0,0,0,0,0,0,0,0,AM32,0,0,0,0)';
      PINUSE='POWER';
      NO_LOAD_CHECK='Both';
      NO_IO_CHECK='Both';
      NO_ASSERT_CHECK='TRUE';
      NO_DIR_CHECK='TRUE';
      ALLOW_CONNECT='TRUE';
    'VCCPRIM_AVID'<14>:
      PIN_NUMBER='(0,0,0,0,0,0,0,0,0,AM34,0,0,0,0)';
      PINUSE='POWER';
      NO_LOAD_CHECK='Both';
      NO_IO_CHECK='Both';
      NO_ASSERT_CHECK='TRUE';
      NO_DIR_CHECK='TRUE';
      ALLOW_CONNECT='TRUE';
    'VCCPRIM_AVID'<13>:
      PIN_NUMBER='(0,0,0,0,0,0,0,0,0,AM36,0,0,0,0)';
      PINUSE='POWER';
      NO_LOAD_CHECK='Both';
      NO_IO_CHECK='Both';
      NO_ASSERT_CHECK='TRUE';
      NO_DIR_CHECK='TRUE';
      ALLOW_CONNECT='TRUE';
    'VCCPRIM_AVID'<12>:
      PIN_NUMBER='(0,0,0,0,0,0,0,0,0,AM37,0,0,0,0)';
      PINUSE='POWER';
      NO_LOAD_CHECK='Both';
      NO_IO_CHECK='Both';
      NO_ASSERT_CHECK='TRUE';
      NO_DIR_CHECK='TRUE';
      ALLOW_CONNECT='TRUE';
    'VCCPRIM_AVID'<11>:
      PIN_NUMBER='(0,0,0,0,0,0,0,0,0,AM39,0,0,0,0)';
      PINUSE='POWER';
      NO_LOAD_CHECK='Both';
      NO_IO_CHECK='Both';
      NO_ASSERT_CHECK='TRUE';
      NO_DIR_CHECK='TRUE';
      ALLOW_CONNECT='TRUE';
    'VCCPRIM_AVID'<10>:
      PIN_NUMBER='(0,0,0,0,0,0,0,0,0,AP32,0,0,0,0)';
      PINUSE='POWER';
      NO_LOAD_CHECK='Both';
      NO_IO_CHECK='Both';
      NO_ASSERT_CHECK='TRUE';
      NO_DIR_CHECK='TRUE';
      ALLOW_CONNECT='TRUE';
    'VCCPRIM_AVID'<9>:
      PIN_NUMBER='(0,0,0,0,0,0,0,0,0,AP34,0,0,0,0)';
      PINUSE='POWER';
      NO_LOAD_CHECK='Both';
      NO_IO_CHECK='Both';
      NO_ASSERT_CHECK='TRUE';
      NO_DIR_CHECK='TRUE';
      ALLOW_CONNECT='TRUE';
    'VCCPRIM_AVID'<8>:
      PIN_NUMBER='(0,0,0,0,0,0,0,0,0,AP36,0,0,0,0)';
      PINUSE='POWER';
      NO_LOAD_CHECK='Both';
      NO_IO_CHECK='Both';
      NO_ASSERT_CHECK='TRUE';
      NO_DIR_CHECK='TRUE';
      ALLOW_CONNECT='TRUE';
    'VCCPRIM_AVID'<7>:
      PIN_NUMBER='(0,0,0,0,0,0,0,0,0,AP37,0,0,0,0)';
      PINUSE='POWER';
      NO_LOAD_CHECK='Both';
      NO_IO_CHECK='Both';
      NO_ASSERT_CHECK='TRUE';
      NO_DIR_CHECK='TRUE';
      ALLOW_CONNECT='TRUE';
    'VCCPRIM_AVID'<6>:
      PIN_NUMBER='(0,0,0,0,0,0,0,0,0,AP39,0,0,0,0)';
      PINUSE='POWER';
      NO_LOAD_CHECK='Both';
      NO_IO_CHECK='Both';
      NO_ASSERT_CHECK='TRUE';
      NO_DIR_CHECK='TRUE';
      ALLOW_CONNECT='TRUE';
    'VCCPRIM_AVID'<5>:
      PIN_NUMBER='(0,0,0,0,0,0,0,0,0,AT32,0,0,0,0)';
      PINUSE='POWER';
      NO_LOAD_CHECK='Both';
      NO_IO_CHECK='Both';
      NO_ASSERT_CHECK='TRUE';
      NO_DIR_CHECK='TRUE';
      ALLOW_CONNECT='TRUE';
    'VCCPRIM_AVID'<4>:
      PIN_NUMBER='(0,0,0,0,0,0,0,0,0,AT34,0,0,0,0)';
      PINUSE='POWER';
      NO_LOAD_CHECK='Both';
      NO_IO_CHECK='Both';
      NO_ASSERT_CHECK='TRUE';
      NO_DIR_CHECK='TRUE';
      ALLOW_CONNECT='TRUE';
    'VCCPRIM_AVID'<3>:
      PIN_NUMBER='(0,0,0,0,0,0,0,0,0,AT36,0,0,0,0)';
      PINUSE='POWER';
      NO_LOAD_CHECK='Both';
      NO_IO_CHECK='Both';
      NO_ASSERT_CHECK='TRUE';
      NO_DIR_CHECK='TRUE';
      ALLOW_CONNECT='TRUE';
    'VCCPRIM_AVID'<2>:
      PIN_NUMBER='(0,0,0,0,0,0,0,0,0,AU32,0,0,0,0)';
      PINUSE='POWER';
      NO_LOAD_CHECK='Both';
      NO_IO_CHECK='Both';
      NO_ASSERT_CHECK='TRUE';
      NO_DIR_CHECK='TRUE';
      ALLOW_CONNECT='TRUE';
    'VCCPRIM_AVID'<1>:
      PIN_NUMBER='(0,0,0,0,0,0,0,0,0,AU34,0,0,0,0)';
      PINUSE='POWER';
      NO_LOAD_CHECK='Both';
      NO_IO_CHECK='Both';
      NO_ASSERT_CHECK='TRUE';
      NO_DIR_CHECK='TRUE';
      ALLOW_CONNECT='TRUE';
    'VCCPRIM_AVID'<0>:
      PIN_NUMBER='(0,0,0,0,0,0,0,0,0,AU36,0,0,0,0)';
      PINUSE='POWER';
      NO_LOAD_CHECK='Both';
      NO_IO_CHECK='Both';
      NO_ASSERT_CHECK='TRUE';
      NO_DIR_CHECK='TRUE';
      ALLOW_CONNECT='TRUE';
    'VCCPRIM_AVID_QAT_SENSE':
      PIN_NUMBER='(0,0,0,0,0,0,0,0,0,V37,0,0,0,0)';
      PINUSE='UNSPEC';
      NO_LOAD_CHECK='Both';
      NO_IO_CHECK='Both';
      NO_ASSERT_CHECK='TRUE';
      NO_DIR_CHECK='TRUE';
      ALLOW_CONNECT='TRUE';
    'VCCPRIM_AVID_SENSE':
      PIN_NUMBER='(0,0,0,0,0,0,0,0,0,AK36,0,0,0,0)';
      BIDIRECTIONAL='TRUE';
      INPUT_LOAD='(-0.01,0.01)';
      OUTPUT_LOAD='(1.0,-1.0)';
    'VCCPRTC':
      PIN_NUMBER='(0,0,0,0,0,0,0,0,AJ27,0,0,0,0,0)';
      PINUSE='POWER';
      NO_LOAD_CHECK='Both';
      NO_IO_CHECK='Both';
      NO_ASSERT_CHECK='TRUE';
      NO_DIR_CHECK='TRUE';
      ALLOW_CONNECT='TRUE';
    'VCCPRTCPRIM_3P3':
      PIN_NUMBER='(0,0,0,0,0,0,0,0,AG29,0,0,0,0,0)';
      PINUSE='POWER';
      NO_LOAD_CHECK='Both';
      NO_IO_CHECK='Both';
      NO_ASSERT_CHECK='TRUE';
      NO_DIR_CHECK='TRUE';
      ALLOW_CONNECT='TRUE';
    'VCCPSPI':
      PIN_NUMBER='(0,0,0,0,0,0,0,0,AR24,0,0,0,0,0)';
      PINUSE='POWER';
      NO_LOAD_CHECK='Both';
      NO_IO_CHECK='Both';
      NO_ASSERT_CHECK='TRUE';
      NO_DIR_CHECK='TRUE';
      ALLOW_CONNECT='TRUE';
    'VCCPSPI_1P8':
      PIN_NUMBER='(0,0,0,0,0,0,0,0,AK29,0,0,0,0,0)';
      PINUSE='POWER';
      NO_LOAD_CHECK='Both';
      NO_IO_CHECK='Both';
      NO_ASSERT_CHECK='TRUE';
      NO_DIR_CHECK='TRUE';
      ALLOW_CONNECT='TRUE';
    'VCCPUSBDSW_3P3':
      PIN_NUMBER='(0,0,0,0,0,0,0,0,BA48,0,0,0,0,0)';
      PINUSE='POWER';
      NO_LOAD_CHECK='Both';
      NO_IO_CHECK='Both';
      NO_ASSERT_CHECK='TRUE';
      NO_DIR_CHECK='TRUE';
      ALLOW_CONNECT='TRUE';
    'VCCP_1P8'<1>:
      PIN_NUMBER='(0,0,0,0,0,0,0,0,AE26,0,0,0,0,0)';
      PINUSE='POWER';
      NO_LOAD_CHECK='Both';
      NO_IO_CHECK='Both';
      NO_ASSERT_CHECK='TRUE';
      NO_DIR_CHECK='TRUE';
      ALLOW_CONNECT='TRUE';
    'VCCP_1P8'<0>:
      PIN_NUMBER='(0,0,0,0,0,0,0,0,BD46,0,0,0,0,0)';
      PINUSE='POWER';
      NO_LOAD_CHECK='Both';
      NO_IO_CHECK='Both';
      NO_ASSERT_CHECK='TRUE';
      NO_DIR_CHECK='TRUE';
      ALLOW_CONNECT='TRUE';
    'VCCP_3P3'<5>:
      PIN_NUMBER='(0,0,0,0,0,0,0,0,AN24,0,0,0,0,0)';
      PINUSE='UNSPEC';
      NO_LOAD_CHECK='Both';
      NO_IO_CHECK='Both';
      NO_ASSERT_CHECK='TRUE';
      NO_DIR_CHECK='TRUE';
      ALLOW_CONNECT='TRUE';
    'VCCP_3P3'<2>:
      PIN_NUMBER='(0,0,0,0,0,0,0,0,AD24,0,0,0,0,0)';
      PINUSE='POWER';
      NO_LOAD_CHECK='Both';
      NO_IO_CHECK='Both';
      NO_ASSERT_CHECK='TRUE';
      NO_DIR_CHECK='TRUE';
      ALLOW_CONNECT='TRUE';
    'VCCP_3P3'<1>:
      PIN_NUMBER='(0,0,0,0,0,0,0,0,BA45,0,0,0,0,0)';
      PINUSE='POWER';
      NO_LOAD_CHECK='Both';
      NO_IO_CHECK='Both';
      NO_ASSERT_CHECK='TRUE';
      NO_DIR_CHECK='TRUE';
      ALLOW_CONNECT='TRUE';
    'VCCP_3P3'<0>:
      PIN_NUMBER='(0,0,0,0,0,0,0,0,BA46,0,0,0,0,0)';
      PINUSE='POWER';
      NO_LOAD_CHECK='Both';
      NO_IO_CHECK='Both';
      NO_ASSERT_CHECK='TRUE';
      NO_DIR_CHECK='TRUE';
      ALLOW_CONNECT='TRUE';
    'VCCP_HSIOPLLUNF_1P05':
      PIN_NUMBER='(0,0,0,0,0,0,0,0,AT48,0,0,0,0,0)';
      PINUSE='POWER';
      NO_LOAD_CHECK='Both';
      NO_IO_CHECK='Both';
      NO_ASSERT_CHECK='TRUE';
      NO_DIR_CHECK='TRUE';
      ALLOW_CONNECT='TRUE';
    'VCCP_HSIOPLL_1P05'<3>:
      PIN_NUMBER='(0,0,0,0,0,0,0,0,AP48,0,0,0,0,0)';
      PINUSE='POWER';
      NO_LOAD_CHECK='Both';
      NO_IO_CHECK='Both';
      NO_ASSERT_CHECK='TRUE';
      NO_DIR_CHECK='TRUE';
      ALLOW_CONNECT='TRUE';
    'VCCP_HSIOPLL_1P05'<2>:
      PIN_NUMBER='(0,0,0,0,0,0,0,0,AU48,0,0,0,0,0)';
      PINUSE='POWER';
      NO_LOAD_CHECK='Both';
      NO_IO_CHECK='Both';
      NO_ASSERT_CHECK='TRUE';
      NO_DIR_CHECK='TRUE';
      ALLOW_CONNECT='TRUE';
    'VCCP_HSIOPLL_1P05'<0>:
      PIN_NUMBER='(0,0,0,0,0,0,0,0,AW48,0,0,0,0,0)';
      PINUSE='POWER';
      NO_LOAD_CHECK='Both';
      NO_IO_CHECK='Both';
      NO_ASSERT_CHECK='TRUE';
      NO_DIR_CHECK='TRUE';
      ALLOW_CONNECT='TRUE';
    'VCCP_UPPLLUNF_1P05':
      PIN_NUMBER='(0,0,0,0,0,0,0,0,AM48,0,0,0,0,0)';
      PINUSE='POWER';
      NO_LOAD_CHECK='Both';
      NO_IO_CHECK='Both';
      NO_ASSERT_CHECK='TRUE';
      NO_DIR_CHECK='TRUE';
      ALLOW_CONNECT='TRUE';
    'VCCP_UPPLL_1P05'<2>:
      PIN_NUMBER='(0,0,0,0,0,0,0,0,AK50,0,0,0,0,0)';
      PINUSE='POWER';
      NO_LOAD_CHECK='Both';
      NO_IO_CHECK='Both';
      NO_ASSERT_CHECK='TRUE';
      NO_DIR_CHECK='TRUE';
      ALLOW_CONNECT='TRUE';
    'VCCP_UPPLL_1P05'<0>:
      PIN_NUMBER='(0,0,0,0,0,0,0,0,AN50,0,0,0,0,0)';
      PINUSE='POWER';
      NO_LOAD_CHECK='Both';
      NO_IO_CHECK='Both';
      NO_ASSERT_CHECK='TRUE';
      NO_DIR_CHECK='TRUE';
      ALLOW_CONNECT='TRUE';
    'VCCRTCEXT':
      PIN_NUMBER='(0,0,0,0,0,0,0,0,AG22,0,0,0,0,0)';
      PINUSE='POWER';
      NO_LOAD_CHECK='Both';
      NO_IO_CHECK='Both';
      NO_ASSERT_CHECK='TRUE';
      NO_DIR_CHECK='TRUE';
      ALLOW_CONNECT='TRUE';
    'VSS'<494>:
      PIN_NUMBER='(0,0,0,0,0,0,0,0,0,0,BP69,0,0,0)';
      PINUSE='GROUND';
      NO_LOAD_CHECK='Both';
      NO_IO_CHECK='Both';
      NO_ASSERT_CHECK='TRUE';
      NO_DIR_CHECK='TRUE';
      ALLOW_CONNECT='TRUE';
    'VSS'<493>:
      PIN_NUMBER='(0,0,0,0,0,0,0,0,0,0,BT69,0,0,0)';
      PINUSE='GROUND';
      NO_LOAD_CHECK='Both';
      NO_IO_CHECK='Both';
      NO_ASSERT_CHECK='TRUE';
      NO_DIR_CHECK='TRUE';
      ALLOW_CONNECT='TRUE';
    'VSS'<492>:
      PIN_NUMBER='(0,0,0,0,0,0,0,0,0,0,BU70,0,0,0)';
      PINUSE='GROUND';
      NO_LOAD_CHECK='Both';
      NO_IO_CHECK='Both';
      NO_ASSERT_CHECK='TRUE';
      NO_DIR_CHECK='TRUE';
      ALLOW_CONNECT='TRUE';
    'VSS'<491>:
      PIN_NUMBER='(0,0,0,0,0,0,0,0,0,0,BR70,0,0,0)';
      PINUSE='GROUND';
      NO_LOAD_CHECK='Both';
      NO_IO_CHECK='Both';
      NO_ASSERT_CHECK='TRUE';
      NO_DIR_CHECK='TRUE';
      ALLOW_CONNECT='TRUE';
    'VSS'<490>:
      PIN_NUMBER='(0,0,0,0,0,0,0,0,0,0,F70,0,0,0)';
      PINUSE='GROUND';
      NO_LOAD_CHECK='Both';
      NO_IO_CHECK='Both';
      NO_ASSERT_CHECK='TRUE';
      NO_DIR_CHECK='TRUE';
      ALLOW_CONNECT='TRUE';
    'VSS'<489>:
      PIN_NUMBER='(0,0,0,0,0,0,0,0,0,0,E70,0,0,0)';
      PINUSE='GROUND';
      NO_LOAD_CHECK='Both';
      NO_IO_CHECK='Both';
      NO_ASSERT_CHECK='TRUE';
      NO_DIR_CHECK='TRUE';
      ALLOW_CONNECT='TRUE';
    'VSS'<488>:
      PIN_NUMBER='(0,0,0,0,0,0,0,0,0,0,BU3,0,0,0)';
      PINUSE='GROUND';
      NO_LOAD_CHECK='Both';
      NO_IO_CHECK='Both';
      NO_ASSERT_CHECK='TRUE';
      NO_DIR_CHECK='TRUE';
      ALLOW_CONNECT='TRUE';
    'VSS'<487>:
      PIN_NUMBER='(0,0,0,0,0,0,0,0,0,0,BR3,0,0,0)';
      PINUSE='GROUND';
      NO_LOAD_CHECK='Both';
      NO_IO_CHECK='Both';
      NO_ASSERT_CHECK='TRUE';
      NO_DIR_CHECK='TRUE';
      ALLOW_CONNECT='TRUE';
    'VSS'<486>:
      PIN_NUMBER='(0,0,0,0,0,0,0,0,0,0,F3,0,0,0)';
      PINUSE='GROUND';
      NO_LOAD_CHECK='Both';
      NO_IO_CHECK='Both';
      NO_ASSERT_CHECK='TRUE';
      NO_DIR_CHECK='TRUE';
      ALLOW_CONNECT='TRUE';
    'VSS'<485>:
      PIN_NUMBER='(0,0,0,0,0,0,0,0,0,0,E3,0,0,0)';
      PINUSE='GROUND';
      NO_LOAD_CHECK='Both';
      NO_IO_CHECK='Both';
      NO_ASSERT_CHECK='TRUE';
      NO_DIR_CHECK='TRUE';
      ALLOW_CONNECT='TRUE';
    'VSS'<484>:
      PIN_NUMBER='(0,0,0,0,0,0,0,0,0,0,A5,0,0,0)';
      PINUSE='GROUND';
      NO_LOAD_CHECK='Both';
      NO_IO_CHECK='Both';
      NO_ASSERT_CHECK='TRUE';
      NO_DIR_CHECK='TRUE';
      ALLOW_CONNECT='TRUE';
    'VSS'<483>:
      PIN_NUMBER='(0,0,0,0,0,0,0,0,0,0,A7,0,0,0)';
      PINUSE='GROUND';
      NO_LOAD_CHECK='Both';
      NO_IO_CHECK='Both';
      NO_ASSERT_CHECK='TRUE';
      NO_DIR_CHECK='TRUE';
      ALLOW_CONNECT='TRUE';
    'VSS'<482>:
      PIN_NUMBER='(0,0,0,0,0,0,0,0,0,0,A9,0,0,0)';
      PINUSE='GROUND';
      NO_LOAD_CHECK='Both';
      NO_IO_CHECK='Both';
      NO_ASSERT_CHECK='TRUE';
      NO_DIR_CHECK='TRUE';
      ALLOW_CONNECT='TRUE';
    'VSS'<481>:
      PIN_NUMBER='(0,0,0,0,0,0,0,0,0,0,A65,0,0,0)';
      PINUSE='GROUND';
      NO_LOAD_CHECK='Both';
      NO_IO_CHECK='Both';
      NO_ASSERT_CHECK='TRUE';
      NO_DIR_CHECK='TRUE';
      ALLOW_CONNECT='TRUE';
    'VSS'<480>:
      PIN_NUMBER='(0,0,0,0,0,0,0,0,0,0,A66,0,0,0)';
      PINUSE='GROUND';
      NO_LOAD_CHECK='Both';
      NO_IO_CHECK='Both';
      NO_ASSERT_CHECK='TRUE';
      NO_DIR_CHECK='TRUE';
      ALLOW_CONNECT='TRUE';
    'VSS'<479>:
      PIN_NUMBER='(0,0,0,0,0,0,0,0,0,0,A68,0,0,0)';
      PINUSE='GROUND';
      NO_LOAD_CHECK='Both';
      NO_IO_CHECK='Both';
      NO_ASSERT_CHECK='TRUE';
      NO_DIR_CHECK='TRUE';
      ALLOW_CONNECT='TRUE';
    'VSS'<478>:
      PIN_NUMBER='(0,0,0,0,0,0,0,0,0,0,J1,0,0,0)';
      PINUSE='GROUND';
      NO_LOAD_CHECK='Both';
      NO_IO_CHECK='Both';
      NO_ASSERT_CHECK='TRUE';
      NO_DIR_CHECK='TRUE';
      ALLOW_CONNECT='TRUE';
    'VSS'<477>:
      PIN_NUMBER='(0,0,0,0,0,0,0,0,0,0,J72,0,0,0)';
      PINUSE='GROUND';
      NO_LOAD_CHECK='Both';
      NO_IO_CHECK='Both';
      NO_ASSERT_CHECK='TRUE';
      NO_DIR_CHECK='TRUE';
      ALLOW_CONNECT='TRUE';
    'VSS'<476>:
      PIN_NUMBER='(0,0,0,0,0,0,0,0,0,0,BN1,0,0,0)';
      PINUSE='GROUND';
      NO_LOAD_CHECK='Both';
      NO_IO_CHECK='Both';
      NO_ASSERT_CHECK='TRUE';
      NO_DIR_CHECK='TRUE';
      ALLOW_CONNECT='TRUE';
    'VSS'<475>:
      PIN_NUMBER='(0,0,0,0,0,0,0,0,0,0,BN72,0,0,0)';
      PINUSE='GROUND';
      NO_LOAD_CHECK='Both';
      NO_IO_CHECK='Both';
      NO_ASSERT_CHECK='TRUE';
      NO_DIR_CHECK='TRUE';
      ALLOW_CONNECT='TRUE';
    'VSS'<474>:
      PIN_NUMBER='(0,0,0,0,0,0,0,0,0,0,CA68,0,0,0)';
      PINUSE='GROUND';
      NO_LOAD_CHECK='Both';
      NO_IO_CHECK='Both';
      NO_ASSERT_CHECK='TRUE';
      NO_DIR_CHECK='TRUE';
      ALLOW_CONNECT='TRUE';
    'VSS'<473>:
      PIN_NUMBER='(0,0,0,0,0,0,0,0,0,0,CA66,0,0,0)';
      PINUSE='GROUND';
      NO_LOAD_CHECK='Both';
      NO_IO_CHECK='Both';
      NO_ASSERT_CHECK='TRUE';
      NO_DIR_CHECK='TRUE';
      ALLOW_CONNECT='TRUE';
    'VSS'<472>:
      PIN_NUMBER='(0,0,0,0,0,0,0,0,0,0,CA65,0,0,0)';
      PINUSE='GROUND';
      NO_LOAD_CHECK='Both';
      NO_IO_CHECK='Both';
      NO_ASSERT_CHECK='TRUE';
      NO_DIR_CHECK='TRUE';
      ALLOW_CONNECT='TRUE';
    'VSS'<471>:
      PIN_NUMBER='(0,0,0,0,0,0,0,0,0,0,CA9,0,0,0)';
      PINUSE='GROUND';
      NO_LOAD_CHECK='Both';
      NO_IO_CHECK='Both';
      NO_ASSERT_CHECK='TRUE';
      NO_DIR_CHECK='TRUE';
      ALLOW_CONNECT='TRUE';
    'VSS'<470>:
      PIN_NUMBER='(0,0,0,0,0,0,0,0,0,0,CA7,0,0,0)';
      PINUSE='GROUND';
      NO_LOAD_CHECK='Both';
      NO_IO_CHECK='Both';
      NO_ASSERT_CHECK='TRUE';
      NO_DIR_CHECK='TRUE';
      ALLOW_CONNECT='TRUE';
    'VSS'<469>:
      PIN_NUMBER='(0,0,0,0,0,0,0,0,0,0,CA5,0,0,0)';
      PINUSE='GROUND';
      NO_LOAD_CHECK='Both';
      NO_IO_CHECK='Both';
      NO_ASSERT_CHECK='TRUE';
      NO_DIR_CHECK='TRUE';
      ALLOW_CONNECT='TRUE';
    'VSS'<468>:
      PIN_NUMBER='(0,0,0,0,0,0,0,0,0,0,A70,0,0,0)';
      PINUSE='GROUND';
      NO_LOAD_CHECK='Both';
      NO_IO_CHECK='Both';
      NO_ASSERT_CHECK='TRUE';
      NO_DIR_CHECK='TRUE';
      ALLOW_CONNECT='TRUE';
    'VSS'<467>:
      PIN_NUMBER='(0,0,0,0,0,0,0,0,0,0,CA3,0,0,0)';
      PINUSE='GROUND';
      NO_LOAD_CHECK='Both';
      NO_IO_CHECK='Both';
      NO_ASSERT_CHECK='TRUE';
      NO_DIR_CHECK='TRUE';
      ALLOW_CONNECT='TRUE';
    'VSS'<466>:
      PIN_NUMBER='(0,0,0,0,0,0,0,0,0,0,BW1,0,0,0)';
      PINUSE='GROUND';
      NO_LOAD_CHECK='Both';
      NO_IO_CHECK='Both';
      NO_ASSERT_CHECK='TRUE';
      NO_DIR_CHECK='TRUE';
      ALLOW_CONNECT='TRUE';
    'VSS'<465>:
      PIN_NUMBER='(0,0,0,0,0,0,0,0,0,0,BU1,0,0,0)';
      PINUSE='GROUND';
      NO_LOAD_CHECK='Both';
      NO_IO_CHECK='Both';
      NO_ASSERT_CHECK='TRUE';
      NO_DIR_CHECK='TRUE';
      ALLOW_CONNECT='TRUE';
    'VSS'<464>:
      PIN_NUMBER='(0,0,0,0,0,0,0,0,0,0,BR1,0,0,0)';
      PINUSE='GROUND';
      NO_LOAD_CHECK='Both';
      NO_IO_CHECK='Both';
      NO_ASSERT_CHECK='TRUE';
      NO_DIR_CHECK='TRUE';
      ALLOW_CONNECT='TRUE';
    'VSS'<463>:
      PIN_NUMBER='(0,0,0,0,0,0,0,0,0,0,C3,0,0,0)';
      PINUSE='GROUND';
      NO_LOAD_CHECK='Both';
      NO_IO_CHECK='Both';
      NO_ASSERT_CHECK='TRUE';
      NO_DIR_CHECK='TRUE';
      ALLOW_CONNECT='TRUE';
    'VSS'<462>:
      PIN_NUMBER='(0,0,0,0,0,0,0,0,0,0,C72,0,0,0)';
      PINUSE='GROUND';
      NO_LOAD_CHECK='Both';
      NO_IO_CHECK='Both';
      NO_ASSERT_CHECK='TRUE';
      NO_DIR_CHECK='TRUE';
      ALLOW_CONNECT='TRUE';
    'VSS'<461>:
      PIN_NUMBER='(0,0,0,0,0,0,0,0,0,0,E1,0,0,0)';
      PINUSE='GROUND';
      NO_LOAD_CHECK='Both';
      NO_IO_CHECK='Both';
      NO_ASSERT_CHECK='TRUE';
      NO_DIR_CHECK='TRUE';
      ALLOW_CONNECT='TRUE';
    'VSS'<460>:
      PIN_NUMBER='(0,0,0,0,0,0,0,0,0,0,E72,0,0,0)';
      PINUSE='GROUND';
      NO_LOAD_CHECK='Both';
      NO_IO_CHECK='Both';
      NO_ASSERT_CHECK='TRUE';
      NO_DIR_CHECK='TRUE';
      ALLOW_CONNECT='TRUE';
    'VSS'<459>:
      PIN_NUMBER='(0,0,0,0,0,0,0,0,0,0,G1,0,0,0)';
      PINUSE='GROUND';
      NO_LOAD_CHECK='Both';
      NO_IO_CHECK='Both';
      NO_ASSERT_CHECK='TRUE';
      NO_DIR_CHECK='TRUE';
      ALLOW_CONNECT='TRUE';
    'VSS'<458>:
      PIN_NUMBER='(0,0,0,0,0,0,0,0,0,0,G72,0,0,0)';
      PINUSE='GROUND';
      NO_LOAD_CHECK='Both';
      NO_IO_CHECK='Both';
      NO_ASSERT_CHECK='TRUE';
      NO_DIR_CHECK='TRUE';
      ALLOW_CONNECT='TRUE';
    'VSS'<457>:
      PIN_NUMBER='(0,0,0,0,0,0,0,0,0,0,BR72,0,0,0)';
      PINUSE='GROUND';
      NO_LOAD_CHECK='Both';
      NO_IO_CHECK='Both';
      NO_ASSERT_CHECK='TRUE';
      NO_DIR_CHECK='TRUE';
      ALLOW_CONNECT='TRUE';
    'VSS'<456>:
      PIN_NUMBER='(0,0,0,0,0,0,0,0,0,0,BU72,0,0,0)';
      PINUSE='GROUND';
      NO_LOAD_CHECK='Both';
      NO_IO_CHECK='Both';
      NO_ASSERT_CHECK='TRUE';
      NO_DIR_CHECK='TRUE';
      ALLOW_CONNECT='TRUE';
    'VSS'<455>:
      PIN_NUMBER='(0,0,0,0,0,0,0,0,0,0,BW70,0,0,0)';
      PINUSE='GROUND';
      NO_LOAD_CHECK='Both';
      NO_IO_CHECK='Both';
      NO_ASSERT_CHECK='TRUE';
      NO_DIR_CHECK='TRUE';
      ALLOW_CONNECT='TRUE';
    'VSS'<454>:
      PIN_NUMBER='(0,0,0,0,0,0,0,0,0,0,BW72,0,0,0)';
      PINUSE='GROUND';
      NO_LOAD_CHECK='Both';
      NO_IO_CHECK='Both';
      NO_ASSERT_CHECK='TRUE';
      NO_DIR_CHECK='TRUE';
      ALLOW_CONNECT='TRUE';
    'VSS'<453>:
      PIN_NUMBER='(0,0,0,0,0,0,0,0,0,0,CA70,0,0,0)';
      PINUSE='GROUND';
      NO_LOAD_CHECK='Both';
      NO_IO_CHECK='Both';
      NO_ASSERT_CHECK='TRUE';
      NO_DIR_CHECK='TRUE';
      ALLOW_CONNECT='TRUE';
    'VSS'<452>:
      PIN_NUMBER='(0,0,0,0,0,0,0,0,0,0,BB48,0,0,0)';
      PINUSE='GROUND';
      NO_LOAD_CHECK='Both';
      NO_IO_CHECK='Both';
      NO_ASSERT_CHECK='TRUE';
      NO_DIR_CHECK='TRUE';
      ALLOW_CONNECT='TRUE';
    'VSS'<451>:
      PIN_NUMBER='(0,0,0,0,0,0,0,0,0,0,AT37,0,0,0)';
      PINUSE='GROUND';
      NO_LOAD_CHECK='Both';
      NO_IO_CHECK='Both';
      NO_ASSERT_CHECK='TRUE';
      NO_DIR_CHECK='TRUE';
      ALLOW_CONNECT='TRUE';
    'VSS'<450>:
      PIN_NUMBER='(0,0,0,0,0,0,0,0,0,0,Y72,0,0,0)';
      PINUSE='GROUND';
      NO_LOAD_CHECK='Both';
      NO_IO_CHECK='Both';
      NO_ASSERT_CHECK='TRUE';
      NO_DIR_CHECK='TRUE';
      ALLOW_CONNECT='TRUE';
    'VSS'<449>:
      PIN_NUMBER='(0,0,0,0,0,0,0,0,0,0,Y70,0,0,0)';
      PINUSE='GROUND';
      NO_LOAD_CHECK='Both';
      NO_IO_CHECK='Both';
      NO_ASSERT_CHECK='TRUE';
      NO_DIR_CHECK='TRUE';
      ALLOW_CONNECT='TRUE';
    'VSS'<448>:
      PIN_NUMBER='(0,0,0,0,0,0,0,0,0,0,A18,0,0,0)';
      PINUSE='GROUND';
      NO_LOAD_CHECK='Both';
      NO_IO_CHECK='Both';
      NO_ASSERT_CHECK='TRUE';
      NO_DIR_CHECK='TRUE';
      ALLOW_CONNECT='TRUE';
    'VSS'<447>:
      PIN_NUMBER='(0,0,0,0,0,0,0,0,0,0,A22,0,0,0)';
      PINUSE='GROUND';
      NO_LOAD_CHECK='Both';
      NO_IO_CHECK='Both';
      NO_ASSERT_CHECK='TRUE';
      NO_DIR_CHECK='TRUE';
      ALLOW_CONNECT='TRUE';
    'VSS'<446>:
      PIN_NUMBER='(0,0,0,0,0,0,0,0,0,0,A30,0,0,0)';
      PINUSE='GROUND';
      NO_LOAD_CHECK='Both';
      NO_IO_CHECK='Both';
      NO_ASSERT_CHECK='TRUE';
      NO_DIR_CHECK='TRUE';
      ALLOW_CONNECT='TRUE';
    'VSS'<445>:
      PIN_NUMBER='(0,0,0,0,0,0,0,0,0,0,A34,0,0,0)';
      PINUSE='GROUND';
      NO_LOAD_CHECK='Both';
      NO_IO_CHECK='Both';
      NO_ASSERT_CHECK='TRUE';
      NO_DIR_CHECK='TRUE';
      ALLOW_CONNECT='TRUE';
    'VSS'<444>:
      PIN_NUMBER='(0,0,0,0,0,0,0,0,0,0,A37,0,0,0)';
      PINUSE='GROUND';
      NO_LOAD_CHECK='Both';
      NO_IO_CHECK='Both';
      NO_ASSERT_CHECK='TRUE';
      NO_DIR_CHECK='TRUE';
      ALLOW_CONNECT='TRUE';
    'VSS'<443>:
      PIN_NUMBER='(0,0,0,0,0,0,0,0,0,0,A41,0,0,0)';
      PINUSE='GROUND';
      NO_LOAD_CHECK='Both';
      NO_IO_CHECK='Both';
      NO_ASSERT_CHECK='TRUE';
      NO_DIR_CHECK='TRUE';
      ALLOW_CONNECT='TRUE';
    'VSS'<442>:
      PIN_NUMBER='(0,0,0,0,0,0,0,0,0,0,B12,0,0,0)';
      PINUSE='GROUND';
      NO_LOAD_CHECK='Both';
      NO_IO_CHECK='Both';
      NO_ASSERT_CHECK='TRUE';
      NO_DIR_CHECK='TRUE';
      ALLOW_CONNECT='TRUE';
    'VSS'<441>:
      PIN_NUMBER='(0,0,0,0,0,0,0,0,0,0,B19,0,0,0)';
      PINUSE='GROUND';
      NO_LOAD_CHECK='Both';
      NO_IO_CHECK='Both';
      NO_ASSERT_CHECK='TRUE';
      NO_DIR_CHECK='TRUE';
      ALLOW_CONNECT='TRUE';
    'VSS'<440>:
      PIN_NUMBER='(0,0,0,0,0,0,0,0,0,0,B25,0,0,0)';
      PINUSE='GROUND';
      NO_LOAD_CHECK='Both';
      NO_IO_CHECK='Both';
      NO_ASSERT_CHECK='TRUE';
      NO_DIR_CHECK='TRUE';
      ALLOW_CONNECT='TRUE';
    'VSS'<439>:
      PIN_NUMBER='(0,0,0,0,0,0,0,0,0,0,B27,0,0,0)';
      PINUSE='GROUND';
      NO_LOAD_CHECK='Both';
      NO_IO_CHECK='Both';
      NO_ASSERT_CHECK='TRUE';
      NO_DIR_CHECK='TRUE';
      ALLOW_CONNECT='TRUE';
    'VSS'<438>:
      PIN_NUMBER='(0,0,0,0,0,0,0,0,0,0,B47,0,0,0)';
      PINUSE='GROUND';
      NO_LOAD_CHECK='Both';
      NO_IO_CHECK='Both';
      NO_ASSERT_CHECK='TRUE';
      NO_DIR_CHECK='TRUE';
      ALLOW_CONNECT='TRUE';
    'VSS'<437>:
      PIN_NUMBER='(0,0,0,0,0,0,0,0,0,0,C22,0,0,0)';
      PINUSE='GROUND';
      NO_LOAD_CHECK='Both';
      NO_IO_CHECK='Both';
      NO_ASSERT_CHECK='TRUE';
      NO_DIR_CHECK='TRUE';
      ALLOW_CONNECT='TRUE';
    'VSS'<436>:
      PIN_NUMBER='(0,0,0,0,0,0,0,0,0,0,C30,0,0,0)';
      PINUSE='GROUND';
      NO_LOAD_CHECK='Both';
      NO_IO_CHECK='Both';
      NO_ASSERT_CHECK='TRUE';
      NO_DIR_CHECK='TRUE';
      ALLOW_CONNECT='TRUE';
    'VSS'<435>:
      PIN_NUMBER='(0,0,0,0,0,0,0,0,0,0,C34,0,0,0)';
      PINUSE='GROUND';
      NO_LOAD_CHECK='Both';
      NO_IO_CHECK='Both';
      NO_ASSERT_CHECK='TRUE';
      NO_DIR_CHECK='TRUE';
      ALLOW_CONNECT='TRUE';
    'VSS'<434>:
      PIN_NUMBER='(0,0,0,0,0,0,0,0,0,0,C37,0,0,0)';
      PINUSE='GROUND';
      NO_LOAD_CHECK='Both';
      NO_IO_CHECK='Both';
      NO_ASSERT_CHECK='TRUE';
      NO_DIR_CHECK='TRUE';
      ALLOW_CONNECT='TRUE';
    'VSS'<433>:
      PIN_NUMBER='(0,0,0,0,0,0,0,0,0,0,C41,0,0,0)';
      PINUSE='GROUND';
      NO_LOAD_CHECK='Both';
      NO_IO_CHECK='Both';
      NO_ASSERT_CHECK='TRUE';
      NO_DIR_CHECK='TRUE';
      ALLOW_CONNECT='TRUE';
    'VSS'<432>:
      PIN_NUMBER='(0,0,0,0,0,0,0,0,0,0,C65,0,0,0)';
      PINUSE='GROUND';
      NO_LOAD_CHECK='Both';
      NO_IO_CHECK='Both';
      NO_ASSERT_CHECK='TRUE';
      NO_DIR_CHECK='TRUE';
      ALLOW_CONNECT='TRUE';
    'VSS'<431>:
      PIN_NUMBER='(0,0,0,0,0,0,0,0,0,0,D12,0,0,0)';
      PINUSE='GROUND';
      NO_LOAD_CHECK='Both';
      NO_IO_CHECK='Both';
      NO_ASSERT_CHECK='TRUE';
      NO_DIR_CHECK='TRUE';
      ALLOW_CONNECT='TRUE';
    'VSS'<430>:
      PIN_NUMBER='(0,0,0,0,0,0,0,0,0,0,D16,0,0,0)';
      PINUSE='GROUND';
      NO_LOAD_CHECK='Both';
      NO_IO_CHECK='Both';
      NO_ASSERT_CHECK='TRUE';
      NO_DIR_CHECK='TRUE';
      ALLOW_CONNECT='TRUE';
    'VSS'<429>:
      PIN_NUMBER='(0,0,0,0,0,0,0,0,0,0,D19,0,0,0)';
      PINUSE='GROUND';
      NO_LOAD_CHECK='Both';
      NO_IO_CHECK='Both';
      NO_ASSERT_CHECK='TRUE';
      NO_DIR_CHECK='TRUE';
      ALLOW_CONNECT='TRUE';
    'VSS'<428>:
      PIN_NUMBER='(0,0,0,0,0,0,0,0,0,0,D25,0,0,0)';
      PINUSE='GROUND';
      NO_LOAD_CHECK='Both';
      NO_IO_CHECK='Both';
      NO_ASSERT_CHECK='TRUE';
      NO_DIR_CHECK='TRUE';
      ALLOW_CONNECT='TRUE';
    'VSS'<427>:
      PIN_NUMBER='(0,0,0,0,0,0,0,0,0,0,D27,0,0,0)';
      PINUSE='GROUND';
      NO_LOAD_CHECK='Both';
      NO_IO_CHECK='Both';
      NO_ASSERT_CHECK='TRUE';
      NO_DIR_CHECK='TRUE';
      ALLOW_CONNECT='TRUE';
    'VSS'<426>:
      PIN_NUMBER='(0,0,0,0,0,0,0,0,0,0,E59,0,0,0)';
      PINUSE='GROUND';
      NO_LOAD_CHECK='Both';
      NO_IO_CHECK='Both';
      NO_ASSERT_CHECK='TRUE';
      NO_DIR_CHECK='TRUE';
      ALLOW_CONNECT='TRUE';
    'VSS'<425>:
      PIN_NUMBER='(0,0,0,0,0,0,0,0,0,0,E65,0,0,0)';
      PINUSE='GROUND';
      NO_LOAD_CHECK='Both';
      NO_IO_CHECK='Both';
      NO_ASSERT_CHECK='TRUE';
      NO_DIR_CHECK='TRUE';
      ALLOW_CONNECT='TRUE';
    'VSS'<424>:
      PIN_NUMBER='(0,0,0,0,0,0,0,0,0,0,D47,0,0,0)';
      PINUSE='GROUND';
      NO_LOAD_CHECK='Both';
      NO_IO_CHECK='Both';
      NO_ASSERT_CHECK='TRUE';
      NO_DIR_CHECK='TRUE';
      ALLOW_CONNECT='TRUE';
    'VSS'<423>:
      PIN_NUMBER='(0,0,0,0,0,0,0,0,0,0,E11,0,0,0)';
      PINUSE='GROUND';
      NO_LOAD_CHECK='Both';
      NO_IO_CHECK='Both';
      NO_ASSERT_CHECK='TRUE';
      NO_DIR_CHECK='TRUE';
      ALLOW_CONNECT='TRUE';
    'VSS'<422>:
      PIN_NUMBER='(0,0,0,0,0,0,0,0,0,0,E13,0,0,0)';
      PINUSE='GROUND';
      NO_LOAD_CHECK='Both';
      NO_IO_CHECK='Both';
      NO_ASSERT_CHECK='TRUE';
      NO_DIR_CHECK='TRUE';
      ALLOW_CONNECT='TRUE';
    'VSS'<421>:
      PIN_NUMBER='(0,0,0,0,0,0,0,0,0,0,E15,0,0,0)';
      PINUSE='GROUND';
      NO_LOAD_CHECK='Both';
      NO_IO_CHECK='Both';
      NO_ASSERT_CHECK='TRUE';
      NO_DIR_CHECK='TRUE';
      ALLOW_CONNECT='TRUE';
    'VSS'<420>:
      PIN_NUMBER='(0,0,0,0,0,0,0,0,0,0,E20,0,0,0)';
      PINUSE='GROUND';
      NO_LOAD_CHECK='Both';
      NO_IO_CHECK='Both';
      NO_ASSERT_CHECK='TRUE';
      NO_DIR_CHECK='TRUE';
      ALLOW_CONNECT='TRUE';
    'VSS'<419>:
      PIN_NUMBER='(0,0,0,0,0,0,0,0,0,0,E22,0,0,0)';
      PINUSE='GROUND';
      NO_LOAD_CHECK='Both';
      NO_IO_CHECK='Both';
      NO_ASSERT_CHECK='TRUE';
      NO_DIR_CHECK='TRUE';
      ALLOW_CONNECT='TRUE';
    'VSS'<418>:
      PIN_NUMBER='(0,0,0,0,0,0,0,0,0,0,E24,0,0,0)';
      PINUSE='GROUND';
      NO_LOAD_CHECK='Both';
      NO_IO_CHECK='Both';
      NO_ASSERT_CHECK='TRUE';
      NO_DIR_CHECK='TRUE';
      ALLOW_CONNECT='TRUE';
    'VSS'<417>:
      PIN_NUMBER='(0,0,0,0,0,0,0,0,0,0,E26,0,0,0)';
      PINUSE='GROUND';
      NO_LOAD_CHECK='Both';
      NO_IO_CHECK='Both';
      NO_ASSERT_CHECK='TRUE';
      NO_DIR_CHECK='TRUE';
      ALLOW_CONNECT='TRUE';
    'VSS'<416>:
      PIN_NUMBER='(0,0,0,0,0,0,0,0,0,0,E28,0,0,0)';
      PINUSE='GROUND';
      NO_LOAD_CHECK='Both';
      NO_IO_CHECK='Both';
      NO_ASSERT_CHECK='TRUE';
      NO_DIR_CHECK='TRUE';
      ALLOW_CONNECT='TRUE';
    'VSS'<415>:
      PIN_NUMBER='(0,0,0,0,0,0,0,0,0,0,E30,0,0,0)';
      PINUSE='GROUND';
      NO_LOAD_CHECK='Both';
      NO_IO_CHECK='Both';
      NO_ASSERT_CHECK='TRUE';
      NO_DIR_CHECK='TRUE';
      ALLOW_CONNECT='TRUE';
    'VSS'<414>:
      PIN_NUMBER='(0,0,0,0,0,0,0,0,0,0,E32,0,0,0)';
      PINUSE='GROUND';
      NO_LOAD_CHECK='Both';
      NO_IO_CHECK='Both';
      NO_ASSERT_CHECK='TRUE';
      NO_DIR_CHECK='TRUE';
      ALLOW_CONNECT='TRUE';
    'VSS'<413>:
      PIN_NUMBER='(0,0,0,0,0,0,0,0,0,0,E34,0,0,0)';
      PINUSE='GROUND';
      NO_LOAD_CHECK='Both';
      NO_IO_CHECK='Both';
      NO_ASSERT_CHECK='TRUE';
      NO_DIR_CHECK='TRUE';
      ALLOW_CONNECT='TRUE';
    'VSS'<412>:
      PIN_NUMBER='(0,0,0,0,0,0,0,0,0,0,E37,0,0,0)';
      PINUSE='GROUND';
      NO_LOAD_CHECK='Both';
      NO_IO_CHECK='Both';
      NO_ASSERT_CHECK='TRUE';
      NO_DIR_CHECK='TRUE';
      ALLOW_CONNECT='TRUE';
    'VSS'<411>:
      PIN_NUMBER='(0,0,0,0,0,0,0,0,0,0,E39,0,0,0)';
      PINUSE='GROUND';
      NO_LOAD_CHECK='Both';
      NO_IO_CHECK='Both';
      NO_ASSERT_CHECK='TRUE';
      NO_DIR_CHECK='TRUE';
      ALLOW_CONNECT='TRUE';
    'VSS'<410>:
      PIN_NUMBER='(0,0,0,0,0,0,0,0,0,0,E41,0,0,0)';
      PINUSE='GROUND';
      NO_LOAD_CHECK='Both';
      NO_IO_CHECK='Both';
      NO_ASSERT_CHECK='TRUE';
      NO_DIR_CHECK='TRUE';
      ALLOW_CONNECT='TRUE';
    'VSS'<409>:
      PIN_NUMBER='(0,0,0,0,0,0,0,0,0,0,E43,0,0,0)';
      PINUSE='GROUND';
      NO_LOAD_CHECK='Both';
      NO_IO_CHECK='Both';
      NO_ASSERT_CHECK='TRUE';
      NO_DIR_CHECK='TRUE';
      ALLOW_CONNECT='TRUE';
    'VSS'<408>:
      PIN_NUMBER='(0,0,0,0,0,0,0,0,0,0,E45,0,0,0)';
      PINUSE='GROUND';
      NO_LOAD_CHECK='Both';
      NO_IO_CHECK='Both';
      NO_ASSERT_CHECK='TRUE';
      NO_DIR_CHECK='TRUE';
      ALLOW_CONNECT='TRUE';
    'VSS'<407>:
      PIN_NUMBER='(0,0,0,0,0,0,0,0,0,0,E48,0,0,0)';
      PINUSE='GROUND';
      NO_LOAD_CHECK='Both';
      NO_IO_CHECK='Both';
      NO_ASSERT_CHECK='TRUE';
      NO_DIR_CHECK='TRUE';
      ALLOW_CONNECT='TRUE';
    'VSS'<406>:
      PIN_NUMBER='(0,0,0,0,0,0,0,0,0,0,E50,0,0,0)';
      PINUSE='GROUND';
      NO_LOAD_CHECK='Both';
      NO_IO_CHECK='Both';
      NO_ASSERT_CHECK='TRUE';
      NO_DIR_CHECK='TRUE';
      ALLOW_CONNECT='TRUE';
    'VSS'<405>:
      PIN_NUMBER='(0,0,0,0,0,0,0,0,0,0,E52,0,0,0)';
      PINUSE='GROUND';
      NO_LOAD_CHECK='Both';
      NO_IO_CHECK='Both';
      NO_ASSERT_CHECK='TRUE';
      NO_DIR_CHECK='TRUE';
      ALLOW_CONNECT='TRUE';
    'VSS'<404>:
      PIN_NUMBER='(0,0,0,0,0,0,0,0,0,0,E54,0,0,0)';
      PINUSE='GROUND';
      NO_LOAD_CHECK='Both';
      NO_IO_CHECK='Both';
      NO_ASSERT_CHECK='TRUE';
      NO_DIR_CHECK='TRUE';
      ALLOW_CONNECT='TRUE';
    'VSS'<403>:
      PIN_NUMBER='(0,0,0,0,0,0,0,0,0,0,E57,0,0,0)';
      PINUSE='GROUND';
      NO_LOAD_CHECK='Both';
      NO_IO_CHECK='Both';
      NO_ASSERT_CHECK='TRUE';
      NO_DIR_CHECK='TRUE';
      ALLOW_CONNECT='TRUE';
    'VSS'<402>:
      PIN_NUMBER='(0,0,0,0,0,0,0,0,0,0,E6,0,0,0)';
      PINUSE='GROUND';
      NO_LOAD_CHECK='Both';
      NO_IO_CHECK='Both';
      NO_ASSERT_CHECK='TRUE';
      NO_DIR_CHECK='TRUE';
      ALLOW_CONNECT='TRUE';
    'VSS'<401>:
      PIN_NUMBER='(0,0,0,0,0,0,0,0,0,0,E61,0,0,0)';
      PINUSE='GROUND';
      NO_LOAD_CHECK='Both';
      NO_IO_CHECK='Both';
      NO_ASSERT_CHECK='TRUE';
      NO_DIR_CHECK='TRUE';
      ALLOW_CONNECT='TRUE';
    'VSS'<400>:
      PIN_NUMBER='(0,0,0,0,0,0,0,0,0,0,E63,0,0,0)';
      PINUSE='GROUND';
      NO_LOAD_CHECK='Both';
      NO_IO_CHECK='Both';
      NO_ASSERT_CHECK='TRUE';
      NO_DIR_CHECK='TRUE';
      ALLOW_CONNECT='TRUE';
    'VSS'<399>:
      PIN_NUMBER='(0,0,0,0,0,0,0,0,0,0,G59,0,0,0)';
      PINUSE='GROUND';
      NO_LOAD_CHECK='Both';
      NO_IO_CHECK='Both';
      NO_ASSERT_CHECK='TRUE';
      NO_DIR_CHECK='TRUE';
      ALLOW_CONNECT='TRUE';
    'VSS'<398>:
      PIN_NUMBER='(0,0,0,0,0,0,0,0,0,0,E9,0,0,0)';
      PINUSE='GROUND';
      NO_LOAD_CHECK='Both';
      NO_IO_CHECK='Both';
      NO_ASSERT_CHECK='TRUE';
      NO_DIR_CHECK='TRUE';
      ALLOW_CONNECT='TRUE';
    'VSS'<397>:
      PIN_NUMBER='(0,0,0,0,0,0,0,0,0,0,G22,0,0,0)';
      PINUSE='GROUND';
      NO_LOAD_CHECK='Both';
      NO_IO_CHECK='Both';
      NO_ASSERT_CHECK='TRUE';
      NO_DIR_CHECK='TRUE';
      ALLOW_CONNECT='TRUE';
    'VSS'<396>:
      PIN_NUMBER='(0,0,0,0,0,0,0,0,0,0,G29,0,0,0)';
      PINUSE='GROUND';
      NO_LOAD_CHECK='Both';
      NO_IO_CHECK='Both';
      NO_ASSERT_CHECK='TRUE';
      NO_DIR_CHECK='TRUE';
      ALLOW_CONNECT='TRUE';
    'VSS'<395>:
      PIN_NUMBER='(0,0,0,0,0,0,0,0,0,0,G37,0,0,0)';
      PINUSE='GROUND';
      NO_LOAD_CHECK='Both';
      NO_IO_CHECK='Both';
      NO_ASSERT_CHECK='TRUE';
      NO_DIR_CHECK='TRUE';
      ALLOW_CONNECT='TRUE';
    'VSS'<394>:
      PIN_NUMBER='(0,0,0,0,0,0,0,0,0,0,G48,0,0,0)';
      PINUSE='GROUND';
      NO_LOAD_CHECK='Both';
      NO_IO_CHECK='Both';
      NO_ASSERT_CHECK='TRUE';
      NO_DIR_CHECK='TRUE';
      ALLOW_CONNECT='TRUE';
    'VSS'<393>:
      PIN_NUMBER='(0,0,0,0,0,0,0,0,0,0,G6,0,0,0)';
      PINUSE='GROUND';
      NO_LOAD_CHECK='Both';
      NO_IO_CHECK='Both';
      NO_ASSERT_CHECK='TRUE';
      NO_DIR_CHECK='TRUE';
      ALLOW_CONNECT='TRUE';
    'VSS'<392>:
      PIN_NUMBER='(0,0,0,0,0,0,0,0,0,0,G63,0,0,0)';
      PINUSE='GROUND';
      NO_LOAD_CHECK='Both';
      NO_IO_CHECK='Both';
      NO_ASSERT_CHECK='TRUE';
      NO_DIR_CHECK='TRUE';
      ALLOW_CONNECT='TRUE';
    'VSS'<391>:
      PIN_NUMBER='(0,0,0,0,0,0,0,0,0,0,G66,0,0,0)';
      PINUSE='GROUND';
      NO_LOAD_CHECK='Both';
      NO_IO_CHECK='Both';
      NO_ASSERT_CHECK='TRUE';
      NO_DIR_CHECK='TRUE';
      ALLOW_CONNECT='TRUE';
    'VSS'<390>:
      PIN_NUMBER='(0,0,0,0,0,0,0,0,0,0,H58,0,0,0)';
      PINUSE='GROUND';
      NO_LOAD_CHECK='Both';
      NO_IO_CHECK='Both';
      NO_ASSERT_CHECK='TRUE';
      NO_DIR_CHECK='TRUE';
      ALLOW_CONNECT='TRUE';
    'VSS'<389>:
      PIN_NUMBER='(0,0,0,0,0,0,0,0,0,0,J29,0,0,0)';
      PINUSE='GROUND';
      NO_LOAD_CHECK='Both';
      NO_IO_CHECK='Both';
      NO_ASSERT_CHECK='TRUE';
      NO_DIR_CHECK='TRUE';
      ALLOW_CONNECT='TRUE';
    'VSS'<388>:
      PIN_NUMBER='(0,0,0,0,0,0,0,0,0,0,J5,0,0,0)';
      PINUSE='GROUND';
      NO_LOAD_CHECK='Both';
      NO_IO_CHECK='Both';
      NO_ASSERT_CHECK='TRUE';
      NO_DIR_CHECK='TRUE';
      ALLOW_CONNECT='TRUE';
    'VSS'<387>:
      PIN_NUMBER='(0,0,0,0,0,0,0,0,0,0,J7,0,0,0)';
      PINUSE='GROUND';
      NO_LOAD_CHECK='Both';
      NO_IO_CHECK='Both';
      NO_ASSERT_CHECK='TRUE';
      NO_DIR_CHECK='TRUE';
      ALLOW_CONNECT='TRUE';
    'VSS'<386>:
      PIN_NUMBER='(0,0,0,0,0,0,0,0,0,0,H65,0,0,0)';
      PINUSE='GROUND';
      NO_LOAD_CHECK='Both';
      NO_IO_CHECK='Both';
      NO_ASSERT_CHECK='TRUE';
      NO_DIR_CHECK='TRUE';
      ALLOW_CONNECT='TRUE';
    'VSS'<385>:
      PIN_NUMBER='(0,0,0,0,0,0,0,0,0,0,J11,0,0,0)';
      PINUSE='GROUND';
      NO_LOAD_CHECK='Both';
      NO_IO_CHECK='Both';
      NO_ASSERT_CHECK='TRUE';
      NO_DIR_CHECK='TRUE';
      ALLOW_CONNECT='TRUE';
    'VSS'<384>:
      PIN_NUMBER='(0,0,0,0,0,0,0,0,0,0,J15,0,0,0)';
      PINUSE='GROUND';
      NO_LOAD_CHECK='Both';
      NO_IO_CHECK='Both';
      NO_ASSERT_CHECK='TRUE';
      NO_DIR_CHECK='TRUE';
      ALLOW_CONNECT='TRUE';
    'VSS'<383>:
      PIN_NUMBER='(0,0,0,0,0,0,0,0,0,0,J22,0,0,0)';
      PINUSE='GROUND';
      NO_LOAD_CHECK='Both';
      NO_IO_CHECK='Both';
      NO_ASSERT_CHECK='TRUE';
      NO_DIR_CHECK='TRUE';
      ALLOW_CONNECT='TRUE';
    'VSS'<382>:
      PIN_NUMBER='(0,0,0,0,0,0,0,0,0,0,J37,0,0,0)';
      PINUSE='GROUND';
      NO_LOAD_CHECK='Both';
      NO_IO_CHECK='Both';
      NO_ASSERT_CHECK='TRUE';
      NO_DIR_CHECK='TRUE';
      ALLOW_CONNECT='TRUE';
    'VSS'<381>:
      PIN_NUMBER='(0,0,0,0,0,0,0,0,0,0,J44,0,0,0)';
      PINUSE='GROUND';
      NO_LOAD_CHECK='Both';
      NO_IO_CHECK='Both';
      NO_ASSERT_CHECK='TRUE';
      NO_DIR_CHECK='TRUE';
      ALLOW_CONNECT='TRUE';
    'VSS'<380>:
      PIN_NUMBER='(0,0,0,0,0,0,0,0,0,0,J59,0,0,0)';
      PINUSE='GROUND';
      NO_LOAD_CHECK='Both';
      NO_IO_CHECK='Both';
      NO_ASSERT_CHECK='TRUE';
      NO_DIR_CHECK='TRUE';
      ALLOW_CONNECT='TRUE';
    'VSS'<379>:
      PIN_NUMBER='(0,0,0,0,0,0,0,0,0,0,J68,0,0,0)';
      PINUSE='GROUND';
      NO_LOAD_CHECK='Both';
      NO_IO_CHECK='Both';
      NO_ASSERT_CHECK='TRUE';
      NO_DIR_CHECK='TRUE';
      ALLOW_CONNECT='TRUE';
    'VSS'<378>:
      PIN_NUMBER='(0,0,0,0,0,0,0,0,0,0,J70,0,0,0)';
      PINUSE='GROUND';
      NO_LOAD_CHECK='Both';
      NO_IO_CHECK='Both';
      NO_ASSERT_CHECK='TRUE';
      NO_DIR_CHECK='TRUE';
      ALLOW_CONNECT='TRUE';
    'VSS'<377>:
      PIN_NUMBER='(0,0,0,0,0,0,0,0,0,0,K54,0,0,0)';
      PINUSE='GROUND';
      NO_LOAD_CHECK='Both';
      NO_IO_CHECK='Both';
      NO_ASSERT_CHECK='TRUE';
      NO_DIR_CHECK='TRUE';
      ALLOW_CONNECT='TRUE';
    'VSS'<376>:
      PIN_NUMBER='(0,0,0,0,0,0,0,0,0,0,K69,0,0,0)';
      PINUSE='GROUND';
      NO_LOAD_CHECK='Both';
      NO_IO_CHECK='Both';
      NO_ASSERT_CHECK='TRUE';
      NO_DIR_CHECK='TRUE';
      ALLOW_CONNECT='TRUE';
    'VSS'<375>:
      PIN_NUMBER='(0,0,0,0,0,0,0,0,0,0,K71,0,0,0)';
      PINUSE='GROUND';
      NO_LOAD_CHECK='Both';
      NO_IO_CHECK='Both';
      NO_ASSERT_CHECK='TRUE';
      NO_DIR_CHECK='TRUE';
      ALLOW_CONNECT='TRUE';
    'VSS'<374>:
      PIN_NUMBER='(0,0,0,0,0,0,0,0,0,0,L5,0,0,0)';
      PINUSE='GROUND';
      NO_LOAD_CHECK='Both';
      NO_IO_CHECK='Both';
      NO_ASSERT_CHECK='TRUE';
      NO_DIR_CHECK='TRUE';
      ALLOW_CONNECT='TRUE';
    'VSS'<373>:
      PIN_NUMBER='(0,0,0,0,0,0,0,0,0,0,L68,0,0,0)';
      PINUSE='GROUND';
      NO_LOAD_CHECK='Both';
      NO_IO_CHECK='Both';
      NO_ASSERT_CHECK='TRUE';
      NO_DIR_CHECK='TRUE';
      ALLOW_CONNECT='TRUE';
    'VSS'<372>:
      PIN_NUMBER='(0,0,0,0,0,0,0,0,0,0,M2,0,0,0)';
      PINUSE='GROUND';
      NO_LOAD_CHECK='Both';
      NO_IO_CHECK='Both';
      NO_ASSERT_CHECK='TRUE';
      NO_DIR_CHECK='TRUE';
      ALLOW_CONNECT='TRUE';
    'VSS'<371>:
      PIN_NUMBER='(0,0,0,0,0,0,0,0,0,0,M22,0,0,0)';
      PINUSE='GROUND';
      NO_LOAD_CHECK='Both';
      NO_IO_CHECK='Both';
      NO_ASSERT_CHECK='TRUE';
      NO_DIR_CHECK='TRUE';
      ALLOW_CONNECT='TRUE';
    'VSS'<370>:
      PIN_NUMBER='(0,0,0,0,0,0,0,0,0,0,M26,0,0,0)';
      PINUSE='GROUND';
      NO_LOAD_CHECK='Both';
      NO_IO_CHECK='Both';
      NO_ASSERT_CHECK='TRUE';
      NO_DIR_CHECK='TRUE';
      ALLOW_CONNECT='TRUE';
    'VSS'<369>:
      PIN_NUMBER='(0,0,0,0,0,0,0,0,0,0,M29,0,0,0)';
      PINUSE='GROUND';
      NO_LOAD_CHECK='Both';
      NO_IO_CHECK='Both';
      NO_ASSERT_CHECK='TRUE';
      NO_DIR_CHECK='TRUE';
      ALLOW_CONNECT='TRUE';
    'VSS'<368>:
      PIN_NUMBER='(0,0,0,0,0,0,0,0,0,0,M33,0,0,0)';
      PINUSE='GROUND';
      NO_LOAD_CHECK='Both';
      NO_IO_CHECK='Both';
      NO_ASSERT_CHECK='TRUE';
      NO_DIR_CHECK='TRUE';
      ALLOW_CONNECT='TRUE';
    'VSS'<367>:
      PIN_NUMBER='(0,0,0,0,0,0,0,0,0,0,M37,0,0,0)';
      PINUSE='GROUND';
      NO_LOAD_CHECK='Both';
      NO_IO_CHECK='Both';
      NO_ASSERT_CHECK='TRUE';
      NO_DIR_CHECK='TRUE';
      ALLOW_CONNECT='TRUE';
    'VSS'<366>:
      PIN_NUMBER='(0,0,0,0,0,0,0,0,0,0,M4,0,0,0)';
      PINUSE='GROUND';
      NO_LOAD_CHECK='Both';
      NO_IO_CHECK='Both';
      NO_ASSERT_CHECK='TRUE';
      NO_DIR_CHECK='TRUE';
      ALLOW_CONNECT='TRUE';
    'VSS'<365>:
      PIN_NUMBER='(0,0,0,0,0,0,0,0,0,0,M40,0,0,0)';
      PINUSE='GROUND';
      NO_LOAD_CHECK='Both';
      NO_IO_CHECK='Both';
      NO_ASSERT_CHECK='TRUE';
      NO_DIR_CHECK='TRUE';
      ALLOW_CONNECT='TRUE';
    'VSS'<364>:
      PIN_NUMBER='(0,0,0,0,0,0,0,0,0,0,N42,0,0,0)';
      PINUSE='GROUND';
      NO_LOAD_CHECK='Both';
      NO_IO_CHECK='Both';
      NO_ASSERT_CHECK='TRUE';
      NO_DIR_CHECK='TRUE';
      ALLOW_CONNECT='TRUE';
    'VSS'<363>:
      PIN_NUMBER='(0,0,0,0,0,0,0,0,0,0,N50,0,0,0)';
      PINUSE='GROUND';
      NO_LOAD_CHECK='Both';
      NO_IO_CHECK='Both';
      NO_ASSERT_CHECK='TRUE';
      NO_DIR_CHECK='TRUE';
      ALLOW_CONNECT='TRUE';
    'VSS'<362>:
      PIN_NUMBER='(0,0,0,0,0,0,0,0,0,0,M44,0,0,0)';
      PINUSE='GROUND';
      NO_LOAD_CHECK='Both';
      NO_IO_CHECK='Both';
      NO_ASSERT_CHECK='TRUE';
      NO_DIR_CHECK='TRUE';
      ALLOW_CONNECT='TRUE';
    'VSS'<361>:
      PIN_NUMBER='(0,0,0,0,0,0,0,0,0,0,M48,0,0,0)';
      PINUSE='GROUND';
      NO_LOAD_CHECK='Both';
      NO_IO_CHECK='Both';
      NO_ASSERT_CHECK='TRUE';
      NO_DIR_CHECK='TRUE';
      ALLOW_CONNECT='TRUE';
    'VSS'<360>:
      PIN_NUMBER='(0,0,0,0,0,0,0,0,0,0,N13,0,0,0)';
      PINUSE='GROUND';
      NO_LOAD_CHECK='Both';
      NO_IO_CHECK='Both';
      NO_ASSERT_CHECK='TRUE';
      NO_DIR_CHECK='TRUE';
      ALLOW_CONNECT='TRUE';
    'VSS'<359>:
      PIN_NUMBER='(0,0,0,0,0,0,0,0,0,0,N17,0,0,0)';
      PINUSE='GROUND';
      NO_LOAD_CHECK='Both';
      NO_IO_CHECK='Both';
      NO_ASSERT_CHECK='TRUE';
      NO_DIR_CHECK='TRUE';
      ALLOW_CONNECT='TRUE';
    'VSS'<358>:
      PIN_NUMBER='(0,0,0,0,0,0,0,0,0,0,N20,0,0,0)';
      PINUSE='GROUND';
      NO_LOAD_CHECK='Both';
      NO_IO_CHECK='Both';
      NO_ASSERT_CHECK='TRUE';
      NO_DIR_CHECK='TRUE';
      ALLOW_CONNECT='TRUE';
    'VSS'<357>:
      PIN_NUMBER='(0,0,0,0,0,0,0,0,0,0,N24,0,0,0)';
      PINUSE='GROUND';
      NO_LOAD_CHECK='Both';
      NO_IO_CHECK='Both';
      NO_ASSERT_CHECK='TRUE';
      NO_DIR_CHECK='TRUE';
      ALLOW_CONNECT='TRUE';
    'VSS'<356>:
      PIN_NUMBER='(0,0,0,0,0,0,0,0,0,0,N27,0,0,0)';
      PINUSE='GROUND';
      NO_LOAD_CHECK='Both';
      NO_IO_CHECK='Both';
      NO_ASSERT_CHECK='TRUE';
      NO_DIR_CHECK='TRUE';
      ALLOW_CONNECT='TRUE';
    'VSS'<355>:
      PIN_NUMBER='(0,0,0,0,0,0,0,0,0,0,N31,0,0,0)';
      PINUSE='GROUND';
      NO_LOAD_CHECK='Both';
      NO_IO_CHECK='Both';
      NO_ASSERT_CHECK='TRUE';
      NO_DIR_CHECK='TRUE';
      ALLOW_CONNECT='TRUE';
    'VSS'<354>:
      PIN_NUMBER='(0,0,0,0,0,0,0,0,0,0,0,N35,0,0)';
      PINUSE='GROUND';
      NO_LOAD_CHECK='Both';
      NO_IO_CHECK='Both';
      NO_ASSERT_CHECK='TRUE';
      NO_DIR_CHECK='TRUE';
      ALLOW_CONNECT='TRUE';
    'VSS'<353>:
      PIN_NUMBER='(0,0,0,0,0,0,0,0,0,0,0,N38,0,0)';
      PINUSE='GROUND';
      NO_LOAD_CHECK='Both';
      NO_IO_CHECK='Both';
      NO_ASSERT_CHECK='TRUE';
      NO_DIR_CHECK='TRUE';
      ALLOW_CONNECT='TRUE';
    'VSS'<352>:
      PIN_NUMBER='(0,0,0,0,0,0,0,0,0,0,0,N46,0,0)';
      PINUSE='GROUND';
      NO_LOAD_CHECK='Both';
      NO_IO_CHECK='Both';
      NO_ASSERT_CHECK='TRUE';
      NO_DIR_CHECK='TRUE';
      ALLOW_CONNECT='TRUE';
    'VSS'<351>:
      PIN_NUMBER='(0,0,0,0,0,0,0,0,0,0,0,N5,0,0)';
      PINUSE='GROUND';
      NO_LOAD_CHECK='Both';
      NO_IO_CHECK='Both';
      NO_ASSERT_CHECK='TRUE';
      NO_DIR_CHECK='TRUE';
      ALLOW_CONNECT='TRUE';
    'VSS'<350>:
      PIN_NUMBER='(0,0,0,0,0,0,0,0,0,0,0,R38,0,0)';
      PINUSE='GROUND';
      NO_LOAD_CHECK='Both';
      NO_IO_CHECK='Both';
      NO_ASSERT_CHECK='TRUE';
      NO_DIR_CHECK='TRUE';
      ALLOW_CONNECT='TRUE';
    'VSS'<349>:
      PIN_NUMBER='(0,0,0,0,0,0,0,0,0,0,0,N68,0,0)';
      PINUSE='GROUND';
      NO_LOAD_CHECK='Both';
      NO_IO_CHECK='Both';
      NO_ASSERT_CHECK='TRUE';
      NO_DIR_CHECK='TRUE';
      ALLOW_CONNECT='TRUE';
    'VSS'<348>:
      PIN_NUMBER='(0,0,0,0,0,0,0,0,0,0,0,N9,0,0)';
      PINUSE='GROUND';
      NO_LOAD_CHECK='Both';
      NO_IO_CHECK='Both';
      NO_ASSERT_CHECK='TRUE';
      NO_DIR_CHECK='TRUE';
      ALLOW_CONNECT='TRUE';
    'VSS'<347>:
      PIN_NUMBER='(0,0,0,0,0,0,0,0,0,0,0,AE43,0,0)';
      PINUSE='GROUND';
      NO_LOAD_CHECK='Both';
      NO_IO_CHECK='Both';
      NO_ASSERT_CHECK='TRUE';
      NO_DIR_CHECK='TRUE';
      ALLOW_CONNECT='TRUE';
    'VSS'<346>:
      PIN_NUMBER='(0,0,0,0,0,0,0,0,0,0,0,P63,0,0)';
      PINUSE='GROUND';
      NO_LOAD_CHECK='Both';
      NO_IO_CHECK='Both';
      NO_ASSERT_CHECK='TRUE';
      NO_DIR_CHECK='TRUE';
      ALLOW_CONNECT='TRUE';
    'VSS'<345>:
      PIN_NUMBER='(0,0,0,0,0,0,0,0,0,0,0,R27,0,0)';
      PINUSE='GROUND';
      NO_LOAD_CHECK='Both';
      NO_IO_CHECK='Both';
      NO_ASSERT_CHECK='TRUE';
      NO_DIR_CHECK='TRUE';
      ALLOW_CONNECT='TRUE';
    'VSS'<344>:
      PIN_NUMBER='(0,0,0,0,0,0,0,0,0,0,0,U42,0,0)';
      PINUSE='GROUND';
      NO_LOAD_CHECK='Both';
      NO_IO_CHECK='Both';
      NO_ASSERT_CHECK='TRUE';
      NO_DIR_CHECK='TRUE';
      ALLOW_CONNECT='TRUE';
    'VSS'<343>:
      PIN_NUMBER='(0,0,0,0,0,0,0,0,0,0,0,R5,0,0)';
      PINUSE='GROUND';
      NO_LOAD_CHECK='Both';
      NO_IO_CHECK='Both';
      NO_ASSERT_CHECK='TRUE';
      NO_DIR_CHECK='TRUE';
      ALLOW_CONNECT='TRUE';
    'VSS'<342>:
      PIN_NUMBER='(0,0,0,0,0,0,0,0,0,0,0,R50,0,0)';
      PINUSE='GROUND';
      NO_LOAD_CHECK='Both';
      NO_IO_CHECK='Both';
      NO_ASSERT_CHECK='TRUE';
      NO_DIR_CHECK='TRUE';
      ALLOW_CONNECT='TRUE';
    'VSS'<341>:
      PIN_NUMBER='(0,0,0,0,0,0,0,0,0,0,0,R54,0,0)';
      PINUSE='GROUND';
      NO_LOAD_CHECK='Both';
      NO_IO_CHECK='Both';
      NO_ASSERT_CHECK='TRUE';
      NO_DIR_CHECK='TRUE';
      ALLOW_CONNECT='TRUE';
    'VSS'<340>:
      PIN_NUMBER='(0,0,0,0,0,0,0,0,0,0,0,T56,0,0)';
      PINUSE='GROUND';
      NO_LOAD_CHECK='Both';
      NO_IO_CHECK='Both';
      NO_ASSERT_CHECK='TRUE';
      NO_DIR_CHECK='TRUE';
      ALLOW_CONNECT='TRUE';
    'VSS'<339>:
      PIN_NUMBER='(0,0,0,0,0,0,0,0,0,0,0,R58,0,0)';
      PINUSE='GROUND';
      NO_LOAD_CHECK='Both';
      NO_IO_CHECK='Both';
      NO_ASSERT_CHECK='TRUE';
      NO_DIR_CHECK='TRUE';
      ALLOW_CONNECT='TRUE';
    'VSS'<338>:
      PIN_NUMBER='(0,0,0,0,0,0,0,0,0,0,0,R68,0,0)';
      PINUSE='GROUND';
      NO_LOAD_CHECK='Both';
      NO_IO_CHECK='Both';
      NO_ASSERT_CHECK='TRUE';
      NO_DIR_CHECK='TRUE';
      ALLOW_CONNECT='TRUE';
    'VSS'<337>:
      PIN_NUMBER='(0,0,0,0,0,0,0,0,0,0,0,T11,0,0)';
      PINUSE='GROUND';
      NO_LOAD_CHECK='Both';
      NO_IO_CHECK='Both';
      NO_ASSERT_CHECK='TRUE';
      NO_DIR_CHECK='TRUE';
      ALLOW_CONNECT='TRUE';
    'VSS'<336>:
      PIN_NUMBER='(0,0,0,0,0,0,0,0,0,0,0,T15,0,0)';
      PINUSE='GROUND';
      NO_LOAD_CHECK='Both';
      NO_IO_CHECK='Both';
      NO_ASSERT_CHECK='TRUE';
      NO_DIR_CHECK='TRUE';
      ALLOW_CONNECT='TRUE';
    'VSS'<335>:
      PIN_NUMBER='(0,0,0,0,0,0,0,0,0,0,0,T18,0,0)';
      PINUSE='GROUND';
      NO_LOAD_CHECK='Both';
      NO_IO_CHECK='Both';
      NO_ASSERT_CHECK='TRUE';
      NO_DIR_CHECK='TRUE';
      ALLOW_CONNECT='TRUE';
    'VSS'<334>:
      PIN_NUMBER='(0,0,0,0,0,0,0,0,0,0,0,T22,0,0)';
      PINUSE='GROUND';
      NO_LOAD_CHECK='Both';
      NO_IO_CHECK='Both';
      NO_ASSERT_CHECK='TRUE';
      NO_DIR_CHECK='TRUE';
      ALLOW_CONNECT='TRUE';
    'VSS'<333>:
      PIN_NUMBER='(0,0,0,0,0,0,0,0,0,0,0,T26,0,0)';
      PINUSE='GROUND';
      NO_LOAD_CHECK='Both';
      NO_IO_CHECK='Both';
      NO_ASSERT_CHECK='TRUE';
      NO_DIR_CHECK='TRUE';
      ALLOW_CONNECT='TRUE';
    'VSS'<332>:
      PIN_NUMBER='(0,0,0,0,0,0,0,0,0,0,0,T29,0,0)';
      PINUSE='GROUND';
      NO_LOAD_CHECK='Both';
      NO_IO_CHECK='Both';
      NO_ASSERT_CHECK='TRUE';
      NO_DIR_CHECK='TRUE';
      ALLOW_CONNECT='TRUE';
    'VSS'<331>:
      PIN_NUMBER='(0,0,0,0,0,0,0,0,0,0,0,T33,0,0)';
      PINUSE='GROUND';
      NO_LOAD_CHECK='Both';
      NO_IO_CHECK='Both';
      NO_ASSERT_CHECK='TRUE';
      NO_DIR_CHECK='TRUE';
      ALLOW_CONNECT='TRUE';
    'VSS'<330>:
      PIN_NUMBER='(0,0,0,0,0,0,0,0,0,0,0,T37,0,0)';
      PINUSE='GROUND';
      NO_LOAD_CHECK='Both';
      NO_IO_CHECK='Both';
      NO_ASSERT_CHECK='TRUE';
      NO_DIR_CHECK='TRUE';
      ALLOW_CONNECT='TRUE';
    'VSS'<329>:
      PIN_NUMBER='(0,0,0,0,0,0,0,0,0,0,0,T40,0,0)';
      PINUSE='GROUND';
      NO_LOAD_CHECK='Both';
      NO_IO_CHECK='Both';
      NO_ASSERT_CHECK='TRUE';
      NO_DIR_CHECK='TRUE';
      ALLOW_CONNECT='TRUE';
    'VSS'<328>:
      PIN_NUMBER='(0,0,0,0,0,0,0,0,0,0,0,AJ45,0,0)';
      PINUSE='GROUND';
      NO_LOAD_CHECK='Both';
      NO_IO_CHECK='Both';
      NO_ASSERT_CHECK='TRUE';
      NO_DIR_CHECK='TRUE';
      ALLOW_CONNECT='TRUE';
    'VSS'<327>:
      PIN_NUMBER='(0,0,0,0,0,0,0,0,0,0,0,T48,0,0)';
      PINUSE='GROUND';
      NO_LOAD_CHECK='Both';
      NO_IO_CHECK='Both';
      NO_ASSERT_CHECK='TRUE';
      NO_DIR_CHECK='TRUE';
      ALLOW_CONNECT='TRUE';
    'VSS'<326>:
      PIN_NUMBER='(0,0,0,0,0,0,0,0,0,0,0,T52,0,0)';
      PINUSE='GROUND';
      NO_LOAD_CHECK='Both';
      NO_IO_CHECK='Both';
      NO_ASSERT_CHECK='TRUE';
      NO_DIR_CHECK='TRUE';
      ALLOW_CONNECT='TRUE';
    'VSS'<325>:
      PIN_NUMBER='(0,0,0,0,0,0,0,0,0,0,0,T66,0,0)';
      PINUSE='GROUND';
      NO_LOAD_CHECK='Both';
      NO_IO_CHECK='Both';
      NO_ASSERT_CHECK='TRUE';
      NO_DIR_CHECK='TRUE';
      ALLOW_CONNECT='TRUE';
    'VSS'<324>:
      PIN_NUMBER='(0,0,0,0,0,0,0,0,0,0,0,T7,0,0)';
      PINUSE='GROUND';
      NO_LOAD_CHECK='Both';
      NO_IO_CHECK='Both';
      NO_ASSERT_CHECK='TRUE';
      NO_DIR_CHECK='TRUE';
      ALLOW_CONNECT='TRUE';
    'VSS'<323>:
      PIN_NUMBER='(0,0,0,0,0,0,0,0,0,0,0,AF50,0,0)';
      PINUSE='GROUND';
      NO_LOAD_CHECK='Both';
      NO_IO_CHECK='Both';
      NO_ASSERT_CHECK='TRUE';
      NO_DIR_CHECK='TRUE';
      ALLOW_CONNECT='TRUE';
    'VSS'<322>:
      PIN_NUMBER='(0,0,0,0,0,0,0,0,0,0,0,AG46,0,0)';
      PINUSE='GROUND';
      NO_LOAD_CHECK='Both';
      NO_IO_CHECK='Both';
      NO_ASSERT_CHECK='TRUE';
      NO_DIR_CHECK='TRUE';
      ALLOW_CONNECT='TRUE';
    'VSS'<321>:
      PIN_NUMBER='(0,0,0,0,0,0,0,0,0,0,0,U58,0,0)';
      PINUSE='GROUND';
      NO_LOAD_CHECK='Both';
      NO_IO_CHECK='Both';
      NO_ASSERT_CHECK='TRUE';
      NO_DIR_CHECK='TRUE';
      ALLOW_CONNECT='TRUE';
    'VSS'<320>:
      PIN_NUMBER='(0,0,0,0,0,0,0,0,0,0,0,V26,0,0)';
      PINUSE='GROUND';
      NO_LOAD_CHECK='Both';
      NO_IO_CHECK='Both';
      NO_ASSERT_CHECK='TRUE';
      NO_DIR_CHECK='TRUE';
      ALLOW_CONNECT='TRUE';
    'VSS'<319>:
      PIN_NUMBER='(0,0,0,0,0,0,0,0,0,0,0,V48,0,0)';
      PINUSE='GROUND';
      NO_LOAD_CHECK='Both';
      NO_IO_CHECK='Both';
      NO_ASSERT_CHECK='TRUE';
      NO_DIR_CHECK='TRUE';
      ALLOW_CONNECT='TRUE';
    'VSS'<318>:
      PIN_NUMBER='(0,0,0,0,0,0,0,0,0,0,0,V5,0,0)';
      PINUSE='GROUND';
      NO_LOAD_CHECK='Both';
      NO_IO_CHECK='Both';
      NO_ASSERT_CHECK='TRUE';
      NO_DIR_CHECK='TRUE';
      ALLOW_CONNECT='TRUE';
    'VSS'<317>:
      PIN_NUMBER='(0,0,0,0,0,0,0,0,0,0,0,V52,0,0)';
      PINUSE='GROUND';
      NO_LOAD_CHECK='Both';
      NO_IO_CHECK='Both';
      NO_ASSERT_CHECK='TRUE';
      NO_DIR_CHECK='TRUE';
      ALLOW_CONNECT='TRUE';
    'VSS'<316>:
      PIN_NUMBER='(0,0,0,0,0,0,0,0,0,0,0,W58,0,0)';
      PINUSE='GROUND';
      NO_LOAD_CHECK='Both';
      NO_IO_CHECK='Both';
      NO_ASSERT_CHECK='TRUE';
      NO_DIR_CHECK='TRUE';
      ALLOW_CONNECT='TRUE';
    'VSS'<315>:
      PIN_NUMBER='(0,0,0,0,0,0,0,0,0,0,0,V66,0,0)';
      PINUSE='GROUND';
      NO_LOAD_CHECK='Both';
      NO_IO_CHECK='Both';
      NO_ASSERT_CHECK='TRUE';
      NO_DIR_CHECK='TRUE';
      ALLOW_CONNECT='TRUE';
    'VSS'<314>:
      PIN_NUMBER='(0,0,0,0,0,0,0,0,0,0,0,V68,0,0)';
      PINUSE='GROUND';
      NO_LOAD_CHECK='Both';
      NO_IO_CHECK='Both';
      NO_ASSERT_CHECK='TRUE';
      NO_DIR_CHECK='TRUE';
      ALLOW_CONNECT='TRUE';
    'VSS'<313>:
      PIN_NUMBER='(0,0,0,0,0,0,0,0,0,0,0,W13,0,0)';
      PINUSE='GROUND';
      NO_LOAD_CHECK='Both';
      NO_IO_CHECK='Both';
      NO_ASSERT_CHECK='TRUE';
      NO_DIR_CHECK='TRUE';
      ALLOW_CONNECT='TRUE';
    'VSS'<312>:
      PIN_NUMBER='(0,0,0,0,0,0,0,0,0,0,0,W17,0,0)';
      PINUSE='GROUND';
      NO_LOAD_CHECK='Both';
      NO_IO_CHECK='Both';
      NO_ASSERT_CHECK='TRUE';
      NO_DIR_CHECK='TRUE';
      ALLOW_CONNECT='TRUE';
    'VSS'<311>:
      PIN_NUMBER='(0,0,0,0,0,0,0,0,0,0,0,W20,0,0)';
      PINUSE='GROUND';
      NO_LOAD_CHECK='Both';
      NO_IO_CHECK='Both';
      NO_ASSERT_CHECK='TRUE';
      NO_DIR_CHECK='TRUE';
      ALLOW_CONNECT='TRUE';
    'VSS'<310>:
      PIN_NUMBER='(0,0,0,0,0,0,0,0,0,0,0,W24,0,0)';
      PINUSE='GROUND';
      NO_LOAD_CHECK='Both';
      NO_IO_CHECK='Both';
      NO_ASSERT_CHECK='TRUE';
      NO_DIR_CHECK='TRUE';
      ALLOW_CONNECT='TRUE';
    'VSS'<309>:
      PIN_NUMBER='(0,0,0,0,0,0,0,0,0,0,0,AA50,0,0)';
      PINUSE='GROUND';
      NO_LOAD_CHECK='Both';
      NO_IO_CHECK='Both';
      NO_ASSERT_CHECK='TRUE';
      NO_DIR_CHECK='TRUE';
      ALLOW_CONNECT='TRUE';
    'VSS'<308>:
      PIN_NUMBER='(0,0,0,0,0,0,0,0,0,0,0,Y43,0,0)';
      PINUSE='GROUND';
      NO_LOAD_CHECK='Both';
      NO_IO_CHECK='Both';
      NO_ASSERT_CHECK='TRUE';
      NO_DIR_CHECK='TRUE';
      ALLOW_CONNECT='TRUE';
    'VSS'<307>:
      PIN_NUMBER='(0,0,0,0,0,0,0,0,0,0,0,W61,0,0)';
      PINUSE='GROUND';
      NO_LOAD_CHECK='Both';
      NO_IO_CHECK='Both';
      NO_ASSERT_CHECK='TRUE';
      NO_DIR_CHECK='TRUE';
      ALLOW_CONNECT='TRUE';
    'VSS'<306>:
      PIN_NUMBER='(0,0,0,0,0,0,0,0,0,0,0,W9,0,0)';
      PINUSE='GROUND';
      NO_LOAD_CHECK='Both';
      NO_IO_CHECK='Both';
      NO_ASSERT_CHECK='TRUE';
      NO_DIR_CHECK='TRUE';
      ALLOW_CONNECT='TRUE';
    'VSS'<305>:
      PIN_NUMBER='(0,0,0,0,0,0,0,0,0,0,0,Y22,0,0)';
      PINUSE='GROUND';
      NO_LOAD_CHECK='Both';
      NO_IO_CHECK='Both';
      NO_ASSERT_CHECK='TRUE';
      NO_DIR_CHECK='TRUE';
      ALLOW_CONNECT='TRUE';
    'VSS'<304>:
      PIN_NUMBER='(0,0,0,0,0,0,0,0,0,0,0,Y27,0,0)';
      PINUSE='GROUND';
      NO_LOAD_CHECK='Both';
      NO_IO_CHECK='Both';
      NO_ASSERT_CHECK='TRUE';
      NO_DIR_CHECK='TRUE';
      ALLOW_CONNECT='TRUE';
    'VSS'<303>:
      PIN_NUMBER='(0,0,0,0,0,0,0,0,0,0,0,Y48,0,0)';
      PINUSE='GROUND';
      NO_LOAD_CHECK='Both';
      NO_IO_CHECK='Both';
      NO_ASSERT_CHECK='TRUE';
      NO_DIR_CHECK='TRUE';
      ALLOW_CONNECT='TRUE';
    'VSS'<302>:
      PIN_NUMBER='(0,0,0,0,0,0,0,0,0,0,0,Y5,0,0)';
      PINUSE='GROUND';
      NO_LOAD_CHECK='Both';
      NO_IO_CHECK='Both';
      NO_ASSERT_CHECK='TRUE';
      NO_DIR_CHECK='TRUE';
      ALLOW_CONNECT='TRUE';
    'VSS'<301>:
      PIN_NUMBER='(0,0,0,0,0,0,0,0,0,0,0,Y52,0,0)';
      PINUSE='GROUND';
      NO_LOAD_CHECK='Both';
      NO_IO_CHECK='Both';
      NO_ASSERT_CHECK='TRUE';
      NO_DIR_CHECK='TRUE';
      ALLOW_CONNECT='TRUE';
    'VSS'<300>:
      PIN_NUMBER='(0,0,0,0,0,0,0,0,0,0,0,Y59,0,0)';
      PINUSE='GROUND';
      NO_LOAD_CHECK='Both';
      NO_IO_CHECK='Both';
      NO_ASSERT_CHECK='TRUE';
      NO_DIR_CHECK='TRUE';
      ALLOW_CONNECT='TRUE';
    'VSS'<299>:
      PIN_NUMBER='(0,0,0,0,0,0,0,0,0,0,0,Y63,0,0)';
      PINUSE='GROUND';
      NO_LOAD_CHECK='Both';
      NO_IO_CHECK='Both';
      NO_ASSERT_CHECK='TRUE';
      NO_DIR_CHECK='TRUE';
      ALLOW_CONNECT='TRUE';
    'VSS'<298>:
      PIN_NUMBER='(0,0,0,0,0,0,0,0,0,0,0,Y68,0,0)';
      PINUSE='GROUND';
      NO_LOAD_CHECK='Both';
      NO_IO_CHECK='Both';
      NO_ASSERT_CHECK='TRUE';
      NO_DIR_CHECK='TRUE';
      ALLOW_CONNECT='TRUE';
    'VSS'<297>:
      PIN_NUMBER='(0,0,0,0,0,0,0,0,0,0,0,AA26,0,0)';
      PINUSE='GROUND';
      NO_LOAD_CHECK='Both';
      NO_IO_CHECK='Both';
      NO_ASSERT_CHECK='TRUE';
      NO_DIR_CHECK='TRUE';
      ALLOW_CONNECT='TRUE';
    'VSS'<296>:
      PIN_NUMBER='(0,0,0,0,0,0,0,0,0,0,0,AA27,0,0)';
      PINUSE='GROUND';
      NO_LOAD_CHECK='Both';
      NO_IO_CHECK='Both';
      NO_ASSERT_CHECK='TRUE';
      NO_DIR_CHECK='TRUE';
      ALLOW_CONNECT='TRUE';
    'VSS'<295>:
      PIN_NUMBER='(0,0,0,0,0,0,0,0,0,0,0,AA43,0,0)';
      PINUSE='GROUND';
      NO_LOAD_CHECK='Both';
      NO_IO_CHECK='Both';
      NO_ASSERT_CHECK='TRUE';
      NO_DIR_CHECK='TRUE';
      ALLOW_CONNECT='TRUE';
    'VSS'<294>:
      PIN_NUMBER='(0,0,0,0,0,0,0,0,0,0,0,AA48,0,0)';
      PINUSE='GROUND';
      NO_LOAD_CHECK='Both';
      NO_IO_CHECK='Both';
      NO_ASSERT_CHECK='TRUE';
      NO_DIR_CHECK='TRUE';
      ALLOW_CONNECT='TRUE';
    'VSS'<293>:
      PIN_NUMBER='(0,0,0,0,0,0,0,0,0,0,0,AB5,0,0)';
      PINUSE='GROUND';
      NO_LOAD_CHECK='Both';
      NO_IO_CHECK='Both';
      NO_ASSERT_CHECK='TRUE';
      NO_DIR_CHECK='TRUE';
      ALLOW_CONNECT='TRUE';
    'VSS'<292>:
      PIN_NUMBER='(0,0,0,0,0,0,0,0,0,0,0,AB68,0,0)';
      PINUSE='GROUND';
      NO_LOAD_CHECK='Both';
      NO_IO_CHECK='Both';
      NO_ASSERT_CHECK='TRUE';
      NO_DIR_CHECK='TRUE';
      ALLOW_CONNECT='TRUE';
    'VSS'<291>:
      PIN_NUMBER='(0,0,0,0,0,0,0,0,0,0,0,AB70,0,0)';
      PINUSE='GROUND';
      NO_LOAD_CHECK='Both';
      NO_IO_CHECK='Both';
      NO_ASSERT_CHECK='TRUE';
      NO_DIR_CHECK='TRUE';
      ALLOW_CONNECT='TRUE';
    'VSS'<290>:
      PIN_NUMBER='(0,0,0,0,0,0,0,0,0,0,0,AB72,0,0)';
      PINUSE='GROUND';
      NO_LOAD_CHECK='Both';
      NO_IO_CHECK='Both';
      NO_ASSERT_CHECK='TRUE';
      NO_DIR_CHECK='TRUE';
      ALLOW_CONNECT='TRUE';
    'VSS'<289>:
      PIN_NUMBER='(0,0,0,0,0,0,0,0,0,0,0,AC11,0,0)';
      PINUSE='GROUND';
      NO_LOAD_CHECK='Both';
      NO_IO_CHECK='Both';
      NO_ASSERT_CHECK='TRUE';
      NO_DIR_CHECK='TRUE';
      ALLOW_CONNECT='TRUE';
    'VSS'<288>:
      PIN_NUMBER='(0,0,0,0,0,0,0,0,0,0,0,AC15,0,0)';
      PINUSE='GROUND';
      NO_LOAD_CHECK='Both';
      NO_IO_CHECK='Both';
      NO_ASSERT_CHECK='TRUE';
      NO_DIR_CHECK='TRUE';
      ALLOW_CONNECT='TRUE';
    'VSS'<287>:
      PIN_NUMBER='(0,0,0,0,0,0,0,0,0,0,0,AC18,0,0)';
      PINUSE='GROUND';
      NO_LOAD_CHECK='Both';
      NO_IO_CHECK='Both';
      NO_ASSERT_CHECK='TRUE';
      NO_DIR_CHECK='TRUE';
      ALLOW_CONNECT='TRUE';
    'VSS'<286>:
      PIN_NUMBER='(0,0,0,0,0,0,0,0,0,0,0,AC22,0,0)';
      PINUSE='GROUND';
      NO_LOAD_CHECK='Both';
      NO_IO_CHECK='Both';
      NO_ASSERT_CHECK='TRUE';
      NO_DIR_CHECK='TRUE';
      ALLOW_CONNECT='TRUE';
    'VSS'<285>:
      PIN_NUMBER='(0,0,0,0,0,0,0,0,0,0,0,AC45,0,0)';
      PINUSE='GROUND';
      NO_LOAD_CHECK='Both';
      NO_IO_CHECK='Both';
      NO_ASSERT_CHECK='TRUE';
      NO_DIR_CHECK='TRUE';
      ALLOW_CONNECT='TRUE';
    'VSS'<284>:
      PIN_NUMBER='(0,0,0,0,0,0,0,0,0,0,0,AD58,0,0)';
      PINUSE='GROUND';
      NO_LOAD_CHECK='Both';
      NO_IO_CHECK='Both';
      NO_ASSERT_CHECK='TRUE';
      NO_DIR_CHECK='TRUE';
      ALLOW_CONNECT='TRUE';
    'VSS'<283>:
      PIN_NUMBER='(0,0,0,0,0,0,0,0,0,0,0,AC27,0,0)';
      PINUSE='GROUND';
      NO_LOAD_CHECK='Both';
      NO_IO_CHECK='Both';
      NO_ASSERT_CHECK='TRUE';
      NO_DIR_CHECK='TRUE';
      ALLOW_CONNECT='TRUE';
    'VSS'<282>:
      PIN_NUMBER='(0,0,0,0,0,0,0,0,0,0,0,AC43,0,0)';
      PINUSE='GROUND';
      NO_LOAD_CHECK='Both';
      NO_IO_CHECK='Both';
      NO_ASSERT_CHECK='TRUE';
      NO_DIR_CHECK='TRUE';
      ALLOW_CONNECT='TRUE';
    'VSS'<281>:
      PIN_NUMBER='(0,0,0,0,0,0,0,0,0,0,0,AC46,0,0)';
      PINUSE='GROUND';
      NO_LOAD_CHECK='Both';
      NO_IO_CHECK='Both';
      NO_ASSERT_CHECK='TRUE';
      NO_DIR_CHECK='TRUE';
      ALLOW_CONNECT='TRUE';
    'VSS'<280>:
      PIN_NUMBER='(0,0,0,0,0,0,0,0,0,0,0,AC48,0,0)';
      PINUSE='GROUND';
      NO_LOAD_CHECK='Both';
      NO_IO_CHECK='Both';
      NO_ASSERT_CHECK='TRUE';
      NO_DIR_CHECK='TRUE';
      ALLOW_CONNECT='TRUE';
    'VSS'<279>:
      PIN_NUMBER='(0,0,0,0,0,0,0,0,0,0,0,AC52,0,0)';
      PINUSE='GROUND';
      NO_LOAD_CHECK='Both';
      NO_IO_CHECK='Both';
      NO_ASSERT_CHECK='TRUE';
      NO_DIR_CHECK='TRUE';
      ALLOW_CONNECT='TRUE';
    'VSS'<278>:
      PIN_NUMBER='(0,0,0,0,0,0,0,0,0,0,0,AC59,0,0)';
      PINUSE='GROUND';
      NO_LOAD_CHECK='Both';
      NO_IO_CHECK='Both';
      NO_ASSERT_CHECK='TRUE';
      NO_DIR_CHECK='TRUE';
      ALLOW_CONNECT='TRUE';
    'VSS'<277>:
      PIN_NUMBER='(0,0,0,0,0,0,0,0,0,0,0,AC63,0,0)';
      PINUSE='GROUND';
      NO_LOAD_CHECK='Both';
      NO_IO_CHECK='Both';
      NO_ASSERT_CHECK='TRUE';
      NO_DIR_CHECK='TRUE';
      ALLOW_CONNECT='TRUE';
    'VSS'<276>:
      PIN_NUMBER='(0,0,0,0,0,0,0,0,0,0,0,AC66,0,0)';
      PINUSE='GROUND';
      NO_LOAD_CHECK='Both';
      NO_IO_CHECK='Both';
      NO_ASSERT_CHECK='TRUE';
      NO_DIR_CHECK='TRUE';
      ALLOW_CONNECT='TRUE';
    'VSS'<275>:
      PIN_NUMBER='(0,0,0,0,0,0,0,0,0,0,0,AC7,0,0)';
      PINUSE='GROUND';
      NO_LOAD_CHECK='Both';
      NO_IO_CHECK='Both';
      NO_ASSERT_CHECK='TRUE';
      NO_DIR_CHECK='TRUE';
      ALLOW_CONNECT='TRUE';
    'VSS'<274>:
      PIN_NUMBER='(0,0,0,0,0,0,0,0,0,0,0,AD5,0,0)';
      PINUSE='GROUND';
      NO_LOAD_CHECK='Both';
      NO_IO_CHECK='Both';
      NO_ASSERT_CHECK='TRUE';
      NO_DIR_CHECK='TRUE';
      ALLOW_CONNECT='TRUE';
    'VSS'<273>:
      PIN_NUMBER='(0,0,0,0,0,0,0,0,0,0,0,AD65,0,0)';
      PINUSE='GROUND';
      NO_LOAD_CHECK='Both';
      NO_IO_CHECK='Both';
      NO_ASSERT_CHECK='TRUE';
      NO_DIR_CHECK='TRUE';
      ALLOW_CONNECT='TRUE';
    'VSS'<272>:
      PIN_NUMBER='(0,0,0,0,0,0,0,0,0,0,0,AD68,0,0)';
      PINUSE='GROUND';
      NO_LOAD_CHECK='Both';
      NO_IO_CHECK='Both';
      NO_ASSERT_CHECK='TRUE';
      NO_DIR_CHECK='TRUE';
      ALLOW_CONNECT='TRUE';
    'VSS'<271>:
      PIN_NUMBER='(0,0,0,0,0,0,0,0,0,0,0,AE29,0,0)';
      PINUSE='GROUND';
      NO_LOAD_CHECK='Both';
      NO_IO_CHECK='Both';
      NO_ASSERT_CHECK='TRUE';
      NO_DIR_CHECK='TRUE';
      ALLOW_CONNECT='TRUE';
    'VSS'<270>:
      PIN_NUMBER='(0,0,0,0,0,0,0,0,0,0,0,J18,0,0)';
      PINUSE='GROUND';
      NO_LOAD_CHECK='Both';
      NO_IO_CHECK='Both';
      NO_ASSERT_CHECK='TRUE';
      NO_DIR_CHECK='TRUE';
      ALLOW_CONNECT='TRUE';
    'VSS'<269>:
      PIN_NUMBER='(0,0,0,0,0,0,0,0,0,0,0,AE48,0,0)';
      PINUSE='GROUND';
      NO_LOAD_CHECK='Both';
      NO_IO_CHECK='Both';
      NO_ASSERT_CHECK='TRUE';
      NO_DIR_CHECK='TRUE';
      ALLOW_CONNECT='TRUE';
    'VSS'<268>:
      PIN_NUMBER='(0,0,0,0,0,0,0,0,0,0,0,AE52,0,0)';
      PINUSE='GROUND';
      NO_LOAD_CHECK='Both';
      NO_IO_CHECK='Both';
      NO_ASSERT_CHECK='TRUE';
      NO_DIR_CHECK='TRUE';
      ALLOW_CONNECT='TRUE';
    'VSS'<267>:
      PIN_NUMBER='(0,0,0,0,0,0,0,0,0,0,0,AE56,0,0)';
      PINUSE='GROUND';
      NO_LOAD_CHECK='Both';
      NO_IO_CHECK='Both';
      NO_ASSERT_CHECK='TRUE';
      NO_DIR_CHECK='TRUE';
      ALLOW_CONNECT='TRUE';
    'VSS'<266>:
      PIN_NUMBER='(0,0,0,0,0,0,0,0,0,0,0,AE59,0,0)';
      PINUSE='GROUND';
      NO_LOAD_CHECK='Both';
      NO_IO_CHECK='Both';
      NO_ASSERT_CHECK='TRUE';
      NO_DIR_CHECK='TRUE';
      ALLOW_CONNECT='TRUE';
    'VSS'<265>:
      PIN_NUMBER='(0,0,0,0,0,0,0,0,0,0,0,AE63,0,0)';
      PINUSE='GROUND';
      NO_LOAD_CHECK='Both';
      NO_IO_CHECK='Both';
      NO_ASSERT_CHECK='TRUE';
      NO_DIR_CHECK='TRUE';
      ALLOW_CONNECT='TRUE';
    'VSS'<264>:
      PIN_NUMBER='(0,0,0,0,0,0,0,0,0,0,0,AE66,0,0)';
      PINUSE='GROUND';
      NO_LOAD_CHECK='Both';
      NO_IO_CHECK='Both';
      NO_ASSERT_CHECK='TRUE';
      NO_DIR_CHECK='TRUE';
      ALLOW_CONNECT='TRUE';
    'VSS'<263>:
      PIN_NUMBER='(0,0,0,0,0,0,0,0,0,0,0,AF1,0,0)';
      PINUSE='GROUND';
      NO_LOAD_CHECK='Both';
      NO_IO_CHECK='Both';
      NO_ASSERT_CHECK='TRUE';
      NO_DIR_CHECK='TRUE';
      ALLOW_CONNECT='TRUE';
    'VSS'<262>:
      PIN_NUMBER='(0,0,0,0,0,0,0,0,0,0,0,AF13,0,0)';
      PINUSE='GROUND';
      NO_LOAD_CHECK='Both';
      NO_IO_CHECK='Both';
      NO_ASSERT_CHECK='TRUE';
      NO_DIR_CHECK='TRUE';
      ALLOW_CONNECT='TRUE';
    'VSS'<261>:
      PIN_NUMBER='(0,0,0,0,0,0,0,0,0,0,0,AF5,0,0)';
      PINUSE='GROUND';
      NO_LOAD_CHECK='Both';
      NO_IO_CHECK='Both';
      NO_ASSERT_CHECK='TRUE';
      NO_DIR_CHECK='TRUE';
      ALLOW_CONNECT='TRUE';
    'VSS'<260>:
      PIN_NUMBER='(0,0,0,0,0,0,0,0,0,0,0,AF9,0,0)';
      PINUSE='GROUND';
      NO_LOAD_CHECK='Both';
      NO_IO_CHECK='Both';
      NO_ASSERT_CHECK='TRUE';
      NO_DIR_CHECK='TRUE';
      ALLOW_CONNECT='TRUE';
    'VSS'<259>:
      PIN_NUMBER='(0,0,0,0,0,0,0,0,0,0,0,AF17,0,0)';
      PINUSE='GROUND';
      NO_LOAD_CHECK='Both';
      NO_IO_CHECK='Both';
      NO_ASSERT_CHECK='TRUE';
      NO_DIR_CHECK='TRUE';
      ALLOW_CONNECT='TRUE';
    'VSS'<258>:
      PIN_NUMBER='(0,0,0,0,0,0,0,0,0,0,0,AF24,0,0)';
      PINUSE='GROUND';
      NO_LOAD_CHECK='Both';
      NO_IO_CHECK='Both';
      NO_ASSERT_CHECK='TRUE';
      NO_DIR_CHECK='TRUE';
      ALLOW_CONNECT='TRUE';
    'VSS'<257>:
      PIN_NUMBER='(0,0,0,0,0,0,0,0,0,0,0,AF3,0,0)';
      PINUSE='GROUND';
      NO_LOAD_CHECK='Both';
      NO_IO_CHECK='Both';
      NO_ASSERT_CHECK='TRUE';
      NO_DIR_CHECK='TRUE';
      ALLOW_CONNECT='TRUE';
    'VSS'<256>:
      PIN_NUMBER='(0,0,0,0,0,0,0,0,0,0,0,AF68,0,0)';
      PINUSE='GROUND';
      NO_LOAD_CHECK='Both';
      NO_IO_CHECK='Both';
      NO_ASSERT_CHECK='TRUE';
      NO_DIR_CHECK='TRUE';
      ALLOW_CONNECT='TRUE';
    'VSS'<255>:
      PIN_NUMBER='(0,0,0,0,0,0,0,0,0,0,0,AG26,0,0)';
      PINUSE='GROUND';
      NO_LOAD_CHECK='Both';
      NO_IO_CHECK='Both';
      NO_ASSERT_CHECK='TRUE';
      NO_DIR_CHECK='TRUE';
      ALLOW_CONNECT='TRUE';
    'VSS'<254>:
      PIN_NUMBER='(0,0,0,0,0,0,0,0,0,0,0,AG30,0,0)';
      PINUSE='GROUND';
      NO_LOAD_CHECK='Both';
      NO_IO_CHECK='Both';
      NO_ASSERT_CHECK='TRUE';
      NO_DIR_CHECK='TRUE';
      ALLOW_CONNECT='TRUE';
    'VSS'<253>:
      PIN_NUMBER='(0,0,0,0,0,0,0,0,0,0,0,AG41,0,0)';
      PINUSE='GROUND';
      NO_LOAD_CHECK='Both';
      NO_IO_CHECK='Both';
      NO_ASSERT_CHECK='TRUE';
      NO_DIR_CHECK='TRUE';
      ALLOW_CONNECT='TRUE';
    'VSS'<252>:
      PIN_NUMBER='(0,0,0,0,0,0,0,0,0,0,0,AG43,0,0)';
      PINUSE='GROUND';
      NO_LOAD_CHECK='Both';
      NO_IO_CHECK='Both';
      NO_ASSERT_CHECK='TRUE';
      NO_DIR_CHECK='TRUE';
      ALLOW_CONNECT='TRUE';
    'VSS'<251>:
      PIN_NUMBER='(0,0,0,0,0,0,0,0,0,0,0,AG52,0,0)';
      PINUSE='GROUND';
      NO_LOAD_CHECK='Both';
      NO_IO_CHECK='Both';
      NO_ASSERT_CHECK='TRUE';
      NO_DIR_CHECK='TRUE';
      ALLOW_CONNECT='TRUE';
    'VSS'<250>:
      PIN_NUMBER='(0,0,0,0,0,0,0,0,0,0,0,AG56,0,0)';
      PINUSE='GROUND';
      NO_LOAD_CHECK='Both';
      NO_IO_CHECK='Both';
      NO_ASSERT_CHECK='TRUE';
      NO_DIR_CHECK='TRUE';
      ALLOW_CONNECT='TRUE';
    'VSS'<249>:
      PIN_NUMBER='(0,0,0,0,0,0,0,0,0,0,0,AG59,0,0)';
      PINUSE='GROUND';
      NO_LOAD_CHECK='Both';
      NO_IO_CHECK='Both';
      NO_ASSERT_CHECK='TRUE';
      NO_DIR_CHECK='TRUE';
      ALLOW_CONNECT='TRUE';
    'VSS'<248>:
      PIN_NUMBER='(0,0,0,0,0,0,0,0,0,0,0,AG66,0,0)';
      PINUSE='GROUND';
      NO_LOAD_CHECK='Both';
      NO_IO_CHECK='Both';
      NO_ASSERT_CHECK='TRUE';
      NO_DIR_CHECK='TRUE';
      ALLOW_CONNECT='TRUE';
    'VSS'<247>:
      PIN_NUMBER='(0,0,0,0,0,0,0,0,0,0,0,AH20,0,0)';
      PINUSE='GROUND';
      NO_LOAD_CHECK='Both';
      NO_IO_CHECK='Both';
      NO_ASSERT_CHECK='TRUE';
      NO_DIR_CHECK='TRUE';
      ALLOW_CONNECT='TRUE';
    'VSS'<246>:
      PIN_NUMBER='(0,0,0,0,0,0,0,0,0,0,0,AJ11,0,0)';
      PINUSE='GROUND';
      NO_LOAD_CHECK='Both';
      NO_IO_CHECK='Both';
      NO_ASSERT_CHECK='TRUE';
      NO_DIR_CHECK='TRUE';
      ALLOW_CONNECT='TRUE';
    'VSS'<245>:
      PIN_NUMBER='(0,0,0,0,0,0,0,0,0,0,0,AJ32,0,0)';
      PINUSE='GROUND';
      NO_LOAD_CHECK='Both';
      NO_IO_CHECK='Both';
      NO_ASSERT_CHECK='TRUE';
      NO_DIR_CHECK='TRUE';
      ALLOW_CONNECT='TRUE';
    'VSS'<244>:
      PIN_NUMBER='(0,0,0,0,0,0,0,0,0,0,0,AJ56,0,0)';
      PINUSE='GROUND';
      NO_LOAD_CHECK='Both';
      NO_IO_CHECK='Both';
      NO_ASSERT_CHECK='TRUE';
      NO_DIR_CHECK='TRUE';
      ALLOW_CONNECT='TRUE';
    'VSS'<243>:
      PIN_NUMBER='(0,0,0,0,0,0,0,0,0,0,0,AK30,0,0)';
      PINUSE='GROUND';
      NO_LOAD_CHECK='Both';
      NO_IO_CHECK='Both';
      NO_ASSERT_CHECK='TRUE';
      NO_DIR_CHECK='TRUE';
      ALLOW_CONNECT='TRUE';
    'VSS'<242>:
      PIN_NUMBER='(0,0,0,0,0,0,0,0,0,0,0,AJ15,0,0)';
      PINUSE='GROUND';
      NO_LOAD_CHECK='Both';
      NO_IO_CHECK='Both';
      NO_ASSERT_CHECK='TRUE';
      NO_DIR_CHECK='TRUE';
      ALLOW_CONNECT='TRUE';
    'VSS'<241>:
      PIN_NUMBER='(0,0,0,0,0,0,0,0,0,0,0,AJ18,0,0)';
      PINUSE='GROUND';
      NO_LOAD_CHECK='Both';
      NO_IO_CHECK='Both';
      NO_ASSERT_CHECK='TRUE';
      NO_DIR_CHECK='TRUE';
      ALLOW_CONNECT='TRUE';
    'VSS'<240>:
      PIN_NUMBER='(0,0,0,0,0,0,0,0,0,0,0,AJ22,0,0)';
      PINUSE='GROUND';
      NO_LOAD_CHECK='Both';
      NO_IO_CHECK='Both';
      NO_ASSERT_CHECK='TRUE';
      NO_DIR_CHECK='TRUE';
      ALLOW_CONNECT='TRUE';
    'VSS'<239>:
      PIN_NUMBER='(0,0,0,0,0,0,0,0,0,0,0,AJ26,0,0)';
      PINUSE='GROUND';
      NO_LOAD_CHECK='Both';
      NO_IO_CHECK='Both';
      NO_ASSERT_CHECK='TRUE';
      NO_DIR_CHECK='TRUE';
      ALLOW_CONNECT='TRUE';
    'VSS'<238>:
      PIN_NUMBER='(0,0,0,0,0,0,0,0,0,0,0,AJ30,0,0)';
      PINUSE='GROUND';
      NO_LOAD_CHECK='Both';
      NO_IO_CHECK='Both';
      NO_ASSERT_CHECK='TRUE';
      NO_DIR_CHECK='TRUE';
      ALLOW_CONNECT='TRUE';
    'VSS'<237>:
      PIN_NUMBER='(0,0,0,0,0,0,0,0,0,0,0,AJ34,0,0)';
      PINUSE='GROUND';
      NO_LOAD_CHECK='Both';
      NO_IO_CHECK='Both';
      NO_ASSERT_CHECK='TRUE';
      NO_DIR_CHECK='TRUE';
      ALLOW_CONNECT='TRUE';
    'VSS'<236>:
      PIN_NUMBER='(0,0,0,0,0,0,0,0,0,0,0,AJ36,0,0)';
      PINUSE='GROUND';
      NO_LOAD_CHECK='Both';
      NO_IO_CHECK='Both';
      NO_ASSERT_CHECK='TRUE';
      NO_DIR_CHECK='TRUE';
      ALLOW_CONNECT='TRUE';
    'VSS'<235>:
      PIN_NUMBER='(0,0,0,0,0,0,0,0,0,0,0,AJ37,0,0)';
      PINUSE='GROUND';
      NO_LOAD_CHECK='Both';
      NO_IO_CHECK='Both';
      NO_ASSERT_CHECK='TRUE';
      NO_DIR_CHECK='TRUE';
      ALLOW_CONNECT='TRUE';
    'VSS'<234>:
      PIN_NUMBER='(0,0,0,0,0,0,0,0,0,0,0,AJ39,0,0)';
      PINUSE='GROUND';
      NO_LOAD_CHECK='Both';
      NO_IO_CHECK='Both';
      NO_ASSERT_CHECK='TRUE';
      NO_DIR_CHECK='TRUE';
      ALLOW_CONNECT='TRUE';
    'VSS'<233>:
      PIN_NUMBER='(0,0,0,0,0,0,0,0,0,0,0,AJ41,0,0)';
      PINUSE='GROUND';
      NO_LOAD_CHECK='Both';
      NO_IO_CHECK='Both';
      NO_ASSERT_CHECK='TRUE';
      NO_DIR_CHECK='TRUE';
      ALLOW_CONNECT='TRUE';
    'VSS'<232>:
      PIN_NUMBER='(0,0,0,0,0,0,0,0,0,0,0,AJ5,0,0)';
      PINUSE='GROUND';
      NO_LOAD_CHECK='Both';
      NO_IO_CHECK='Both';
      NO_ASSERT_CHECK='TRUE';
      NO_DIR_CHECK='TRUE';
      ALLOW_CONNECT='TRUE';
    'VSS'<231>:
      PIN_NUMBER='(0,0,0,0,0,0,0,0,0,0,0,AJ52,0,0)';
      PINUSE='GROUND';
      NO_LOAD_CHECK='Both';
      NO_IO_CHECK='Both';
      NO_ASSERT_CHECK='TRUE';
      NO_DIR_CHECK='TRUE';
      ALLOW_CONNECT='TRUE';
    'VSS'<230>:
      PIN_NUMBER='(0,0,0,0,0,0,0,0,0,0,0,AJ59,0,0)';
      PINUSE='GROUND';
      NO_LOAD_CHECK='Both';
      NO_IO_CHECK='Both';
      NO_ASSERT_CHECK='TRUE';
      NO_DIR_CHECK='TRUE';
      ALLOW_CONNECT='TRUE';
    'VSS'<229>:
      PIN_NUMBER='(0,0,0,0,0,0,0,0,0,0,0,AJ66,0,0)';
      PINUSE='GROUND';
      NO_LOAD_CHECK='Both';
      NO_IO_CHECK='Both';
      NO_ASSERT_CHECK='TRUE';
      NO_DIR_CHECK='TRUE';
      ALLOW_CONNECT='TRUE';
    'VSS'<228>:
      PIN_NUMBER='(0,0,0,0,0,0,0,0,0,0,0,AJ68,0,0)';
      PINUSE='GROUND';
      NO_LOAD_CHECK='Both';
      NO_IO_CHECK='Both';
      NO_ASSERT_CHECK='TRUE';
      NO_DIR_CHECK='TRUE';
      ALLOW_CONNECT='TRUE';
    'VSS'<227>:
      PIN_NUMBER='(0,0,0,0,0,0,0,0,0,0,0,AJ7,0,0)';
      PINUSE='GROUND';
      NO_LOAD_CHECK='Both';
      NO_IO_CHECK='Both';
      NO_ASSERT_CHECK='TRUE';
      NO_DIR_CHECK='TRUE';
      ALLOW_CONNECT='TRUE';
    'VSS'<226>:
      PIN_NUMBER='(0,0,0,0,0,0,0,0,0,0,0,AK26,0,0)';
      PINUSE='GROUND';
      NO_LOAD_CHECK='Both';
      NO_IO_CHECK='Both';
      NO_ASSERT_CHECK='TRUE';
      NO_DIR_CHECK='TRUE';
      ALLOW_CONNECT='TRUE';
    'VSS'<225>:
      PIN_NUMBER='(0,0,0,0,0,0,0,0,0,0,0,AK41,0,0)';
      PINUSE='GROUND';
      NO_LOAD_CHECK='Both';
      NO_IO_CHECK='Both';
      NO_ASSERT_CHECK='TRUE';
      NO_DIR_CHECK='TRUE';
      ALLOW_CONNECT='TRUE';
    'VSS'<224>:
      PIN_NUMBER='(0,0,0,0,0,0,0,0,0,0,0,AK46,0,0)';
      PINUSE='GROUND';
      NO_LOAD_CHECK='Both';
      NO_IO_CHECK='Both';
      NO_ASSERT_CHECK='TRUE';
      NO_DIR_CHECK='TRUE';
      ALLOW_CONNECT='TRUE';
    'VSS'<223>:
      PIN_NUMBER='(0,0,0,0,0,0,0,0,0,0,0,AK48,0,0)';
      PINUSE='GROUND';
      NO_LOAD_CHECK='Both';
      NO_IO_CHECK='Both';
      NO_ASSERT_CHECK='TRUE';
      NO_DIR_CHECK='TRUE';
      ALLOW_CONNECT='TRUE';
    'VSS'<222>:
      PIN_NUMBER='(0,0,0,0,0,0,0,0,0,0,0,AK58,0,0)';
      PINUSE='GROUND';
      NO_LOAD_CHECK='Both';
      NO_IO_CHECK='Both';
      NO_ASSERT_CHECK='TRUE';
      NO_DIR_CHECK='TRUE';
      ALLOW_CONNECT='TRUE';
    'VSS'<221>:
      PIN_NUMBER='(0,0,0,0,0,0,0,0,0,0,0,AK61,0,0)';
      PINUSE='GROUND';
      NO_LOAD_CHECK='Both';
      NO_IO_CHECK='Both';
      NO_ASSERT_CHECK='TRUE';
      NO_DIR_CHECK='TRUE';
      ALLOW_CONNECT='TRUE';
    'VSS'<220>:
      PIN_NUMBER='(0,0,0,0,0,0,0,0,0,0,0,AK69,0,0)';
      PINUSE='GROUND';
      NO_LOAD_CHECK='Both';
      NO_IO_CHECK='Both';
      NO_ASSERT_CHECK='TRUE';
      NO_DIR_CHECK='TRUE';
      ALLOW_CONNECT='TRUE';
    'VSS'<219>:
      PIN_NUMBER='(0,0,0,0,0,0,0,0,0,0,0,AK71,0,0)';
      PINUSE='GROUND';
      NO_LOAD_CHECK='Both';
      NO_IO_CHECK='Both';
      NO_ASSERT_CHECK='TRUE';
      NO_DIR_CHECK='TRUE';
      ALLOW_CONNECT='TRUE';
    'VSS'<218>:
      PIN_NUMBER='(0,0,0,0,0,0,0,0,0,0,0,AL22,0,0)';
      PINUSE='GROUND';
      NO_LOAD_CHECK='Both';
      NO_IO_CHECK='Both';
      NO_ASSERT_CHECK='TRUE';
      NO_DIR_CHECK='TRUE';
      ALLOW_CONNECT='TRUE';
    'VSS'<217>:
      PIN_NUMBER='(0,0,0,0,0,0,0,0,0,0,0,AL5,0,0)';
      PINUSE='GROUND';
      NO_LOAD_CHECK='Both';
      NO_IO_CHECK='Both';
      NO_ASSERT_CHECK='TRUE';
      NO_DIR_CHECK='TRUE';
      ALLOW_CONNECT='TRUE';
    'VSS'<216>:
      PIN_NUMBER='(0,0,0,0,0,0,0,0,0,0,0,AL52,0,0)';
      PINUSE='GROUND';
      NO_LOAD_CHECK='Both';
      NO_IO_CHECK='Both';
      NO_ASSERT_CHECK='TRUE';
      NO_DIR_CHECK='TRUE';
      ALLOW_CONNECT='TRUE';
    'VSS'<215>:
      PIN_NUMBER='(0,0,0,0,0,0,0,0,0,0,0,AL59,0,0)';
      PINUSE='GROUND';
      NO_LOAD_CHECK='Both';
      NO_IO_CHECK='Both';
      NO_ASSERT_CHECK='TRUE';
      NO_DIR_CHECK='TRUE';
      ALLOW_CONNECT='TRUE';
    'VSS'<214>:
      PIN_NUMBER='(0,0,0,0,0,0,0,0,0,0,0,0,AL68,0)';
      PINUSE='GROUND';
      NO_LOAD_CHECK='Both';
      NO_IO_CHECK='Both';
      NO_ASSERT_CHECK='TRUE';
      NO_DIR_CHECK='TRUE';
      ALLOW_CONNECT='TRUE';
    'VSS'<213>:
      PIN_NUMBER='(0,0,0,0,0,0,0,0,0,0,0,0,AL70,0)';
      PINUSE='GROUND';
      NO_LOAD_CHECK='Both';
      NO_IO_CHECK='Both';
      NO_ASSERT_CHECK='TRUE';
      NO_DIR_CHECK='TRUE';
      ALLOW_CONNECT='TRUE';
    'VSS'<212>:
      PIN_NUMBER='(0,0,0,0,0,0,0,0,0,0,0,0,AL72,0)';
      PINUSE='GROUND';
      NO_LOAD_CHECK='Both';
      NO_IO_CHECK='Both';
      NO_ASSERT_CHECK='TRUE';
      NO_DIR_CHECK='TRUE';
      ALLOW_CONNECT='TRUE';
    'VSS'<211>:
      PIN_NUMBER='(0,0,0,0,0,0,0,0,0,0,0,0,AM26,0)';
      PINUSE='GROUND';
      NO_LOAD_CHECK='Both';
      NO_IO_CHECK='Both';
      NO_ASSERT_CHECK='TRUE';
      NO_DIR_CHECK='TRUE';
      ALLOW_CONNECT='TRUE';
    'VSS'<210>:
      PIN_NUMBER='(0,0,0,0,0,0,0,0,0,0,0,0,AM30,0)';
      PINUSE='GROUND';
      NO_LOAD_CHECK='Both';
      NO_IO_CHECK='Both';
      NO_ASSERT_CHECK='TRUE';
      NO_DIR_CHECK='TRUE';
      ALLOW_CONNECT='TRUE';
    'VSS'<209>:
      PIN_NUMBER='(0,0,0,0,0,0,0,0,0,0,0,0,AM41,0)';
      PINUSE='GROUND';
      NO_LOAD_CHECK='Both';
      NO_IO_CHECK='Both';
      NO_ASSERT_CHECK='TRUE';
      NO_DIR_CHECK='TRUE';
      ALLOW_CONNECT='TRUE';
    'VSS'<208>:
      PIN_NUMBER='(0,0,0,0,0,0,0,0,0,0,0,0,AM46,0)';
      PINUSE='GROUND';
      NO_LOAD_CHECK='Both';
      NO_IO_CHECK='Both';
      NO_ASSERT_CHECK='TRUE';
      NO_DIR_CHECK='TRUE';
      ALLOW_CONNECT='TRUE';
    'VSS'<207>:
      PIN_NUMBER='(0,0,0,0,0,0,0,0,0,0,0,0,AN13,0)';
      PINUSE='GROUND';
      NO_LOAD_CHECK='Both';
      NO_IO_CHECK='Both';
      NO_ASSERT_CHECK='TRUE';
      NO_DIR_CHECK='TRUE';
      ALLOW_CONNECT='TRUE';
    'VSS'<206>:
      PIN_NUMBER='(0,0,0,0,0,0,0,0,0,0,0,0,AN17,0)';
      PINUSE='GROUND';
      NO_LOAD_CHECK='Both';
      NO_IO_CHECK='Both';
      NO_ASSERT_CHECK='TRUE';
      NO_DIR_CHECK='TRUE';
      ALLOW_CONNECT='TRUE';
    'VSS'<205>:
      PIN_NUMBER='(0,0,0,0,0,0,0,0,0,0,0,0,AN68,0)';
      PINUSE='GROUND';
      NO_LOAD_CHECK='Both';
      NO_IO_CHECK='Both';
      NO_ASSERT_CHECK='TRUE';
      NO_DIR_CHECK='TRUE';
      ALLOW_CONNECT='TRUE';
    'VSS'<204>:
      PIN_NUMBER='(0,0,0,0,0,0,0,0,0,0,0,0,AP22,0)';
      PINUSE='GROUND';
      NO_LOAD_CHECK='Both';
      NO_IO_CHECK='Both';
      NO_ASSERT_CHECK='TRUE';
      NO_DIR_CHECK='TRUE';
      ALLOW_CONNECT='TRUE';
    'VSS'<203>:
      PIN_NUMBER='(0,0,0,0,0,0,0,0,0,0,0,0,AN20,0)';
      PINUSE='GROUND';
      NO_LOAD_CHECK='Both';
      NO_IO_CHECK='Both';
      NO_ASSERT_CHECK='TRUE';
      NO_DIR_CHECK='TRUE';
      ALLOW_CONNECT='TRUE';
    'VSS'<202>:
      PIN_NUMBER='(0,0,0,0,0,0,0,0,0,0,0,0,AN5,0)';
      PINUSE='GROUND';
      NO_LOAD_CHECK='Both';
      NO_IO_CHECK='Both';
      NO_ASSERT_CHECK='TRUE';
      NO_DIR_CHECK='TRUE';
      ALLOW_CONNECT='TRUE';
    'VSS'<201>:
      PIN_NUMBER='(0,0,0,0,0,0,0,0,0,0,0,0,AN58,0)';
      PINUSE='GROUND';
      NO_LOAD_CHECK='Both';
      NO_IO_CHECK='Both';
      NO_ASSERT_CHECK='TRUE';
      NO_DIR_CHECK='TRUE';
      ALLOW_CONNECT='TRUE';
    'VSS'<200>:
      PIN_NUMBER='(0,0,0,0,0,0,0,0,0,0,0,0,AN9,0)';
      PINUSE='GROUND';
      NO_LOAD_CHECK='Both';
      NO_IO_CHECK='Both';
      NO_ASSERT_CHECK='TRUE';
      NO_DIR_CHECK='TRUE';
      ALLOW_CONNECT='TRUE';
    'VSS'<199>:
      PIN_NUMBER='(0,0,0,0,0,0,0,0,0,0,0,0,AP2,0)';
      PINUSE='GROUND';
      NO_LOAD_CHECK='Both';
      NO_IO_CHECK='Both';
      NO_ASSERT_CHECK='TRUE';
      NO_DIR_CHECK='TRUE';
      ALLOW_CONNECT='TRUE';
    'VSS'<198>:
      PIN_NUMBER='(0,0,0,0,0,0,0,0,0,0,0,0,AP26,0)';
      PINUSE='GROUND';
      NO_LOAD_CHECK='Both';
      NO_IO_CHECK='Both';
      NO_ASSERT_CHECK='TRUE';
      NO_DIR_CHECK='TRUE';
      ALLOW_CONNECT='TRUE';
    'VSS'<197>:
      PIN_NUMBER='(0,0,0,0,0,0,0,0,0,0,0,0,AP30,0)';
      PINUSE='GROUND';
      NO_LOAD_CHECK='Both';
      NO_IO_CHECK='Both';
      NO_ASSERT_CHECK='TRUE';
      NO_DIR_CHECK='TRUE';
      ALLOW_CONNECT='TRUE';
    'VSS'<196>:
      PIN_NUMBER='(0,0,0,0,0,0,0,0,0,0,0,0,AP4,0)';
      PINUSE='GROUND';
      NO_LOAD_CHECK='Both';
      NO_IO_CHECK='Both';
      NO_ASSERT_CHECK='TRUE';
      NO_DIR_CHECK='TRUE';
      ALLOW_CONNECT='TRUE';
    'VSS'<195>:
      PIN_NUMBER='(0,0,0,0,0,0,0,0,0,0,0,0,AP41,0)';
      PINUSE='GROUND';
      NO_LOAD_CHECK='Both';
      NO_IO_CHECK='Both';
      NO_ASSERT_CHECK='TRUE';
      NO_DIR_CHECK='TRUE';
      ALLOW_CONNECT='TRUE';
    'VSS'<194>:
      PIN_NUMBER='(0,0,0,0,0,0,0,0,0,0,0,0,AP46,0)';
      PINUSE='GROUND';
      NO_LOAD_CHECK='Both';
      NO_IO_CHECK='Both';
      NO_ASSERT_CHECK='TRUE';
      NO_DIR_CHECK='TRUE';
      ALLOW_CONNECT='TRUE';
    'VSS'<193>:
      PIN_NUMBER='(0,0,0,0,0,0,0,0,0,0,0,0,AP52,0)';
      PINUSE='GROUND';
      NO_LOAD_CHECK='Both';
      NO_IO_CHECK='Both';
      NO_ASSERT_CHECK='TRUE';
      NO_DIR_CHECK='TRUE';
      ALLOW_CONNECT='TRUE';
    'VSS'<192>:
      PIN_NUMBER='(0,0,0,0,0,0,0,0,0,0,0,0,AP66,0)';
      PINUSE='GROUND';
      NO_LOAD_CHECK='Both';
      NO_IO_CHECK='Both';
      NO_ASSERT_CHECK='TRUE';
      NO_DIR_CHECK='TRUE';
      ALLOW_CONNECT='TRUE';
    'VSS'<191>:
      PIN_NUMBER='(0,0,0,0,0,0,0,0,0,0,0,0,AR5,0)';
      PINUSE='GROUND';
      NO_LOAD_CHECK='Both';
      NO_IO_CHECK='Both';
      NO_ASSERT_CHECK='TRUE';
      NO_DIR_CHECK='TRUE';
      ALLOW_CONNECT='TRUE';
    'VSS'<190>:
      PIN_NUMBER='(0,0,0,0,0,0,0,0,0,0,0,0,AR50,0)';
      PINUSE='GROUND';
      NO_LOAD_CHECK='Both';
      NO_IO_CHECK='Both';
      NO_ASSERT_CHECK='TRUE';
      NO_DIR_CHECK='TRUE';
      ALLOW_CONNECT='TRUE';
    'VSS'<189>:
      PIN_NUMBER='(0,0,0,0,0,0,0,0,0,0,0,0,AR58,0)';
      PINUSE='GROUND';
      NO_LOAD_CHECK='Both';
      NO_IO_CHECK='Both';
      NO_ASSERT_CHECK='TRUE';
      NO_DIR_CHECK='TRUE';
      ALLOW_CONNECT='TRUE';
    'VSS'<188>:
      PIN_NUMBER='(0,0,0,0,0,0,0,0,0,0,0,0,AR65,0)';
      PINUSE='GROUND';
      NO_LOAD_CHECK='Both';
      NO_IO_CHECK='Both';
      NO_ASSERT_CHECK='TRUE';
      NO_DIR_CHECK='TRUE';
      ALLOW_CONNECT='TRUE';
    'VSS'<187>:
      PIN_NUMBER='(0,0,0,0,0,0,0,0,0,0,0,0,AR68,0)';
      PINUSE='GROUND';
      NO_LOAD_CHECK='Both';
      NO_IO_CHECK='Both';
      NO_ASSERT_CHECK='TRUE';
      NO_DIR_CHECK='TRUE';
      ALLOW_CONNECT='TRUE';
    'VSS'<186>:
      PIN_NUMBER='(0,0,0,0,0,0,0,0,0,0,0,0,AR70,0)';
      PINUSE='GROUND';
      NO_LOAD_CHECK='Both';
      NO_IO_CHECK='Both';
      NO_ASSERT_CHECK='TRUE';
      NO_DIR_CHECK='TRUE';
      ALLOW_CONNECT='TRUE';
    'VSS'<185>:
      PIN_NUMBER='(0,0,0,0,0,0,0,0,0,0,0,0,AR72,0)';
      PINUSE='GROUND';
      NO_LOAD_CHECK='Both';
      NO_IO_CHECK='Both';
      NO_ASSERT_CHECK='TRUE';
      NO_DIR_CHECK='TRUE';
      ALLOW_CONNECT='TRUE';
    'VSS'<184>:
      PIN_NUMBER='(0,0,0,0,0,0,0,0,0,0,0,0,AT7,0)';
      PINUSE='GROUND';
      NO_LOAD_CHECK='Both';
      NO_IO_CHECK='Both';
      NO_ASSERT_CHECK='TRUE';
      NO_DIR_CHECK='TRUE';
      ALLOW_CONNECT='TRUE';
    'VSS'<183>:
      PIN_NUMBER='(0,0,0,0,0,0,0,0,0,0,0,0,AT11,0)';
      PINUSE='GROUND';
      NO_LOAD_CHECK='Both';
      NO_IO_CHECK='Both';
      NO_ASSERT_CHECK='TRUE';
      NO_DIR_CHECK='TRUE';
      ALLOW_CONNECT='TRUE';
    'VSS'<182>:
      PIN_NUMBER='(0,0,0,0,0,0,0,0,0,0,0,0,AT15,0)';
      PINUSE='GROUND';
      NO_LOAD_CHECK='Both';
      NO_IO_CHECK='Both';
      NO_ASSERT_CHECK='TRUE';
      NO_DIR_CHECK='TRUE';
      ALLOW_CONNECT='TRUE';
    'VSS'<181>:
      PIN_NUMBER='(0,0,0,0,0,0,0,0,0,0,0,0,AT18,0)';
      PINUSE='GROUND';
      NO_LOAD_CHECK='Both';
      NO_IO_CHECK='Both';
      NO_ASSERT_CHECK='TRUE';
      NO_DIR_CHECK='TRUE';
      ALLOW_CONNECT='TRUE';
    'VSS'<180>:
      PIN_NUMBER='(0,0,0,0,0,0,0,0,0,0,0,0,AT22,0)';
      PINUSE='GROUND';
      NO_LOAD_CHECK='Both';
      NO_IO_CHECK='Both';
      NO_ASSERT_CHECK='TRUE';
      NO_DIR_CHECK='TRUE';
      ALLOW_CONNECT='TRUE';
    'VSS'<179>:
      PIN_NUMBER='(0,0,0,0,0,0,0,0,0,0,0,0,AT26,0)';
      PINUSE='GROUND';
      NO_LOAD_CHECK='Both';
      NO_IO_CHECK='Both';
      NO_ASSERT_CHECK='TRUE';
      NO_DIR_CHECK='TRUE';
      ALLOW_CONNECT='TRUE';
    'VSS'<178>:
      PIN_NUMBER='(0,0,0,0,0,0,0,0,0,0,0,0,AT30,0)';
      PINUSE='GROUND';
      NO_LOAD_CHECK='Both';
      NO_IO_CHECK='Both';
      NO_ASSERT_CHECK='TRUE';
      NO_DIR_CHECK='TRUE';
      ALLOW_CONNECT='TRUE';
    'VSS'<177>:
      PIN_NUMBER='(0,0,0,0,0,0,0,0,0,0,0,0,AT41,0)';
      PINUSE='GROUND';
      NO_LOAD_CHECK='Both';
      NO_IO_CHECK='Both';
      NO_ASSERT_CHECK='TRUE';
      NO_DIR_CHECK='TRUE';
      ALLOW_CONNECT='TRUE';
    'VSS'<176>:
      PIN_NUMBER='(0,0,0,0,0,0,0,0,0,0,0,0,AT46,0)';
      PINUSE='GROUND';
      NO_LOAD_CHECK='Both';
      NO_IO_CHECK='Both';
      NO_ASSERT_CHECK='TRUE';
      NO_DIR_CHECK='TRUE';
      ALLOW_CONNECT='TRUE';
    'VSS'<175>:
      PIN_NUMBER='(0,0,0,0,0,0,0,0,0,0,0,0,AT59,0)';
      PINUSE='GROUND';
      NO_LOAD_CHECK='Both';
      NO_IO_CHECK='Both';
      NO_ASSERT_CHECK='TRUE';
      NO_DIR_CHECK='TRUE';
      ALLOW_CONNECT='TRUE';
    'VSS'<174>:
      PIN_NUMBER='(0,0,0,0,0,0,0,0,0,0,0,0,AU26,0)';
      PINUSE='GROUND';
      NO_LOAD_CHECK='Both';
      NO_IO_CHECK='Both';
      NO_ASSERT_CHECK='TRUE';
      NO_DIR_CHECK='TRUE';
      ALLOW_CONNECT='TRUE';
    'VSS'<173>:
      PIN_NUMBER='(0,0,0,0,0,0,0,0,0,0,0,0,AU30,0)';
      PINUSE='GROUND';
      NO_LOAD_CHECK='Both';
      NO_IO_CHECK='Both';
      NO_ASSERT_CHECK='TRUE';
      NO_DIR_CHECK='TRUE';
      ALLOW_CONNECT='TRUE';
    'VSS'<172>:
      PIN_NUMBER='(0,0,0,0,0,0,0,0,0,0,0,0,AE22,0)';
      PINUSE='GROUND';
      NO_LOAD_CHECK='Both';
      NO_IO_CHECK='Both';
      NO_ASSERT_CHECK='TRUE';
      NO_DIR_CHECK='TRUE';
      ALLOW_CONNECT='TRUE';
    'VSS'<171>:
      PIN_NUMBER='(0,0,0,0,0,0,0,0,0,0,0,0,AU41,0)';
      PINUSE='GROUND';
      NO_LOAD_CHECK='Both';
      NO_IO_CHECK='Both';
      NO_ASSERT_CHECK='TRUE';
      NO_DIR_CHECK='TRUE';
      ALLOW_CONNECT='TRUE';
    'VSS'<170>:
      PIN_NUMBER='(0,0,0,0,0,0,0,0,0,0,0,0,AU46,0)';
      PINUSE='GROUND';
      NO_LOAD_CHECK='Both';
      NO_IO_CHECK='Both';
      NO_ASSERT_CHECK='TRUE';
      NO_DIR_CHECK='TRUE';
      ALLOW_CONNECT='TRUE';
    'VSS'<169>:
      PIN_NUMBER='(0,0,0,0,0,0,0,0,0,0,0,0,AU50,0)';
      PINUSE='GROUND';
      NO_LOAD_CHECK='Both';
      NO_IO_CHECK='Both';
      NO_ASSERT_CHECK='TRUE';
      NO_DIR_CHECK='TRUE';
      ALLOW_CONNECT='TRUE';
    'VSS'<168>:
      PIN_NUMBER='(0,0,0,0,0,0,0,0,0,0,0,0,AU54,0)';
      PINUSE='GROUND';
      NO_LOAD_CHECK='Both';
      NO_IO_CHECK='Both';
      NO_ASSERT_CHECK='TRUE';
      NO_DIR_CHECK='TRUE';
      ALLOW_CONNECT='TRUE';
    'VSS'<167>:
      PIN_NUMBER='(0,0,0,0,0,0,0,0,0,0,0,0,AU61,0)';
      PINUSE='GROUND';
      NO_LOAD_CHECK='Both';
      NO_IO_CHECK='Both';
      NO_ASSERT_CHECK='TRUE';
      NO_DIR_CHECK='TRUE';
      ALLOW_CONNECT='TRUE';
    'VSS'<166>:
      PIN_NUMBER='(0,0,0,0,0,0,0,0,0,0,0,0,AV5,0)';
      PINUSE='GROUND';
      NO_LOAD_CHECK='Both';
      NO_IO_CHECK='Both';
      NO_ASSERT_CHECK='TRUE';
      NO_DIR_CHECK='TRUE';
      ALLOW_CONNECT='TRUE';
    'VSS'<165>:
      PIN_NUMBER='(0,0,0,0,0,0,0,0,0,0,0,0,AV22,0)';
      PINUSE='GROUND';
      NO_LOAD_CHECK='Both';
      NO_IO_CHECK='Both';
      NO_ASSERT_CHECK='TRUE';
      NO_DIR_CHECK='TRUE';
      ALLOW_CONNECT='TRUE';
    'VSS'<164>:
      PIN_NUMBER='(0,0,0,0,0,0,0,0,0,0,0,0,AV59,0)';
      PINUSE='GROUND';
      NO_LOAD_CHECK='Both';
      NO_IO_CHECK='Both';
      NO_ASSERT_CHECK='TRUE';
      NO_DIR_CHECK='TRUE';
      ALLOW_CONNECT='TRUE';
    'VSS'<163>:
      PIN_NUMBER='(0,0,0,0,0,0,0,0,0,0,0,0,AV68,0)';
      PINUSE='GROUND';
      NO_LOAD_CHECK='Both';
      NO_IO_CHECK='Both';
      NO_ASSERT_CHECK='TRUE';
      NO_DIR_CHECK='TRUE';
      ALLOW_CONNECT='TRUE';
    'VSS'<162>:
      PIN_NUMBER='(0,0,0,0,0,0,0,0,0,0,0,0,AW9,0)';
      PINUSE='GROUND';
      NO_LOAD_CHECK='Both';
      NO_IO_CHECK='Both';
      NO_ASSERT_CHECK='TRUE';
      NO_DIR_CHECK='TRUE';
      ALLOW_CONNECT='TRUE';
    'VSS'<161>:
      PIN_NUMBER='(0,0,0,0,0,0,0,0,0,0,0,0,AW13,0)';
      PINUSE='GROUND';
      NO_LOAD_CHECK='Both';
      NO_IO_CHECK='Both';
      NO_ASSERT_CHECK='TRUE';
      NO_DIR_CHECK='TRUE';
      ALLOW_CONNECT='TRUE';
    'VSS'<160>:
      PIN_NUMBER='(0,0,0,0,0,0,0,0,0,0,0,0,AW17,0)';
      PINUSE='GROUND';
      NO_LOAD_CHECK='Both';
      NO_IO_CHECK='Both';
      NO_ASSERT_CHECK='TRUE';
      NO_DIR_CHECK='TRUE';
      ALLOW_CONNECT='TRUE';
    'VSS'<159>:
      PIN_NUMBER='(0,0,0,0,0,0,0,0,0,0,0,0,AW26,0)';
      PINUSE='GROUND';
      NO_LOAD_CHECK='Both';
      NO_IO_CHECK='Both';
      NO_ASSERT_CHECK='TRUE';
      NO_DIR_CHECK='TRUE';
      ALLOW_CONNECT='TRUE';
    'VSS'<158>:
      PIN_NUMBER='(0,0,0,0,0,0,0,0,0,0,0,0,AW30,0)';
      PINUSE='GROUND';
      NO_LOAD_CHECK='Both';
      NO_IO_CHECK='Both';
      NO_ASSERT_CHECK='TRUE';
      NO_DIR_CHECK='TRUE';
      ALLOW_CONNECT='TRUE';
    'VSS'<157>:
      PIN_NUMBER='(0,0,0,0,0,0,0,0,0,0,0,0,AW32,0)';
      PINUSE='GROUND';
      NO_LOAD_CHECK='Both';
      NO_IO_CHECK='Both';
      NO_ASSERT_CHECK='TRUE';
      NO_DIR_CHECK='TRUE';
      ALLOW_CONNECT='TRUE';
    'VSS'<156>:
      PIN_NUMBER='(0,0,0,0,0,0,0,0,0,0,0,0,AW34,0)';
      PINUSE='GROUND';
      NO_LOAD_CHECK='Both';
      NO_IO_CHECK='Both';
      NO_ASSERT_CHECK='TRUE';
      NO_DIR_CHECK='TRUE';
      ALLOW_CONNECT='TRUE';
    'VSS'<155>:
      PIN_NUMBER='(0,0,0,0,0,0,0,0,0,0,0,0,AW36,0)';
      PINUSE='GROUND';
      NO_LOAD_CHECK='Both';
      NO_IO_CHECK='Both';
      NO_ASSERT_CHECK='TRUE';
      NO_DIR_CHECK='TRUE';
      ALLOW_CONNECT='TRUE';
    'VSS'<154>:
      PIN_NUMBER='(0,0,0,0,0,0,0,0,0,0,0,0,AW37,0)';
      PINUSE='GROUND';
      NO_LOAD_CHECK='Both';
      NO_IO_CHECK='Both';
      NO_ASSERT_CHECK='TRUE';
      NO_DIR_CHECK='TRUE';
      ALLOW_CONNECT='TRUE';
    'VSS'<153>:
      PIN_NUMBER='(0,0,0,0,0,0,0,0,0,0,0,0,AW39,0)';
      PINUSE='GROUND';
      NO_LOAD_CHECK='Both';
      NO_IO_CHECK='Both';
      NO_ASSERT_CHECK='TRUE';
      NO_DIR_CHECK='TRUE';
      ALLOW_CONNECT='TRUE';
    'VSS'<152>:
      PIN_NUMBER='(0,0,0,0,0,0,0,0,0,0,0,0,AW41,0)';
      PINUSE='GROUND';
      NO_LOAD_CHECK='Both';
      NO_IO_CHECK='Both';
      NO_ASSERT_CHECK='TRUE';
      NO_DIR_CHECK='TRUE';
      ALLOW_CONNECT='TRUE';
    'VSS'<151>:
      PIN_NUMBER='(0,0,0,0,0,0,0,0,0,0,0,0,AW46,0)';
      PINUSE='GROUND';
      NO_LOAD_CHECK='Both';
      NO_IO_CHECK='Both';
      NO_ASSERT_CHECK='TRUE';
      NO_DIR_CHECK='TRUE';
      ALLOW_CONNECT='TRUE';
    'VSS'<150>:
      PIN_NUMBER='(0,0,0,0,0,0,0,0,0,0,0,0,AW50,0)';
      PINUSE='GROUND';
      NO_LOAD_CHECK='Both';
      NO_IO_CHECK='Both';
      NO_ASSERT_CHECK='TRUE';
      NO_DIR_CHECK='TRUE';
      ALLOW_CONNECT='TRUE';
    'VSS'<149>:
      PIN_NUMBER='(0,0,0,0,0,0,0,0,0,0,0,0,AW58,0)';
      PINUSE='GROUND';
      NO_LOAD_CHECK='Both';
      NO_IO_CHECK='Both';
      NO_ASSERT_CHECK='TRUE';
      NO_DIR_CHECK='TRUE';
      ALLOW_CONNECT='TRUE';
    'VSS'<148>:
      PIN_NUMBER='(0,0,0,0,0,0,0,0,0,0,0,0,AW61,0)';
      PINUSE='GROUND';
      NO_LOAD_CHECK='Both';
      NO_IO_CHECK='Both';
      NO_ASSERT_CHECK='TRUE';
      NO_DIR_CHECK='TRUE';
      ALLOW_CONNECT='TRUE';
    'VSS'<147>:
      PIN_NUMBER='(0,0,0,0,0,0,0,0,0,0,0,0,AY5,0)';
      PINUSE='GROUND';
      NO_LOAD_CHECK='Both';
      NO_IO_CHECK='Both';
      NO_ASSERT_CHECK='TRUE';
      NO_DIR_CHECK='TRUE';
      ALLOW_CONNECT='TRUE';
    'VSS'<146>:
      PIN_NUMBER='(0,0,0,0,0,0,0,0,0,0,0,0,AY22,0)';
      PINUSE='GROUND';
      NO_LOAD_CHECK='Both';
      NO_IO_CHECK='Both';
      NO_ASSERT_CHECK='TRUE';
      NO_DIR_CHECK='TRUE';
      ALLOW_CONNECT='TRUE';
    'VSS'<145>:
      PIN_NUMBER='(0,0,0,0,0,0,0,0,0,0,0,0,AY56,0)';
      PINUSE='GROUND';
      NO_LOAD_CHECK='Both';
      NO_IO_CHECK='Both';
      NO_ASSERT_CHECK='TRUE';
      NO_DIR_CHECK='TRUE';
      ALLOW_CONNECT='TRUE';
    'VSS'<144>:
      PIN_NUMBER='(0,0,0,0,0,0,0,0,0,0,0,0,AY63,0)';
      PINUSE='GROUND';
      NO_LOAD_CHECK='Both';
      NO_IO_CHECK='Both';
      NO_ASSERT_CHECK='TRUE';
      NO_DIR_CHECK='TRUE';
      ALLOW_CONNECT='TRUE';
    'VSS'<143>:
      PIN_NUMBER='(0,0,0,0,0,0,0,0,0,0,0,0,AY68,0)';
      PINUSE='GROUND';
      NO_LOAD_CHECK='Both';
      NO_IO_CHECK='Both';
      NO_ASSERT_CHECK='TRUE';
      NO_DIR_CHECK='TRUE';
      ALLOW_CONNECT='TRUE';
    'VSS'<142>:
      PIN_NUMBER='(0,0,0,0,0,0,0,0,0,0,0,0,BA50,0)';
      PINUSE='GROUND';
      NO_LOAD_CHECK='Both';
      NO_IO_CHECK='Both';
      NO_ASSERT_CHECK='TRUE';
      NO_DIR_CHECK='TRUE';
      ALLOW_CONNECT='TRUE';
    'VSS'<141>:
      PIN_NUMBER='(0,0,0,0,0,0,0,0,0,0,0,0,BA54,0)';
      PINUSE='GROUND';
      NO_LOAD_CHECK='Both';
      NO_IO_CHECK='Both';
      NO_ASSERT_CHECK='TRUE';
      NO_DIR_CHECK='TRUE';
      ALLOW_CONNECT='TRUE';
    'VSS'<140>:
      PIN_NUMBER='(0,0,0,0,0,0,0,0,0,0,0,0,BA58,0)';
      PINUSE='GROUND';
      NO_LOAD_CHECK='Both';
      NO_IO_CHECK='Both';
      NO_ASSERT_CHECK='TRUE';
      NO_DIR_CHECK='TRUE';
      ALLOW_CONNECT='TRUE';
    'VSS'<139>:
      PIN_NUMBER='(0,0,0,0,0,0,0,0,0,0,0,0,BB5,0)';
      PINUSE='GROUND';
      NO_LOAD_CHECK='Both';
      NO_IO_CHECK='Both';
      NO_ASSERT_CHECK='TRUE';
      NO_DIR_CHECK='TRUE';
      ALLOW_CONNECT='TRUE';
    'VSS'<138>:
      PIN_NUMBER='(0,0,0,0,0,0,0,0,0,0,0,0,BB7,0)';
      PINUSE='GROUND';
      NO_LOAD_CHECK='Both';
      NO_IO_CHECK='Both';
      NO_ASSERT_CHECK='TRUE';
      NO_DIR_CHECK='TRUE';
      ALLOW_CONNECT='TRUE';
    'VSS'<137>:
      PIN_NUMBER='(0,0,0,0,0,0,0,0,0,0,0,0,BB11,0)';
      PINUSE='GROUND';
      NO_LOAD_CHECK='Both';
      NO_IO_CHECK='Both';
      NO_ASSERT_CHECK='TRUE';
      NO_DIR_CHECK='TRUE';
      ALLOW_CONNECT='TRUE';
    'VSS'<136>:
      PIN_NUMBER='(0,0,0,0,0,0,0,0,0,0,0,0,BB15,0)';
      PINUSE='GROUND';
      NO_LOAD_CHECK='Both';
      NO_IO_CHECK='Both';
      NO_ASSERT_CHECK='TRUE';
      NO_DIR_CHECK='TRUE';
      ALLOW_CONNECT='TRUE';
    'VSS'<135>:
      PIN_NUMBER='(0,0,0,0,0,0,0,0,0,0,0,0,BB18,0)';
      PINUSE='GROUND';
      NO_LOAD_CHECK='Both';
      NO_IO_CHECK='Both';
      NO_ASSERT_CHECK='TRUE';
      NO_DIR_CHECK='TRUE';
      ALLOW_CONNECT='TRUE';
    'VSS'<134>:
      PIN_NUMBER='(0,0,0,0,0,0,0,0,0,0,0,0,BB22,0)';
      PINUSE='GROUND';
      NO_LOAD_CHECK='Both';
      NO_IO_CHECK='Both';
      NO_ASSERT_CHECK='TRUE';
      NO_DIR_CHECK='TRUE';
      ALLOW_CONNECT='TRUE';
    'VSS'<133>:
      PIN_NUMBER='(0,0,0,0,0,0,0,0,0,0,0,0,BB44,0)';
      PINUSE='GROUND';
      NO_LOAD_CHECK='Both';
      NO_IO_CHECK='Both';
      NO_ASSERT_CHECK='TRUE';
      NO_DIR_CHECK='TRUE';
      ALLOW_CONNECT='TRUE';
    'VSS'<132>:
      PIN_NUMBER='(0,0,0,0,0,0,0,0,0,0,0,0,BB59,0)';
      PINUSE='GROUND';
      NO_LOAD_CHECK='Both';
      NO_IO_CHECK='Both';
      NO_ASSERT_CHECK='TRUE';
      NO_DIR_CHECK='TRUE';
      ALLOW_CONNECT='TRUE';
    'VSS'<131>:
      PIN_NUMBER='(0,0,0,0,0,0,0,0,0,0,0,0,BB66,0)';
      PINUSE='GROUND';
      NO_LOAD_CHECK='Both';
      NO_IO_CHECK='Both';
      NO_ASSERT_CHECK='TRUE';
      NO_DIR_CHECK='TRUE';
      ALLOW_CONNECT='TRUE';
    'VSS'<130>:
      PIN_NUMBER='(0,0,0,0,0,0,0,0,0,0,0,0,BB68,0)';
      PINUSE='GROUND';
      NO_LOAD_CHECK='Both';
      NO_IO_CHECK='Both';
      NO_ASSERT_CHECK='TRUE';
      NO_DIR_CHECK='TRUE';
      ALLOW_CONNECT='TRUE';
    'VSS'<129>:
      PIN_NUMBER='(0,0,0,0,0,0,0,0,0,0,0,0,BB70,0)';
      PINUSE='GROUND';
      NO_LOAD_CHECK='Both';
      NO_IO_CHECK='Both';
      NO_ASSERT_CHECK='TRUE';
      NO_DIR_CHECK='TRUE';
      ALLOW_CONNECT='TRUE';
    'VSS'<128>:
      PIN_NUMBER='(0,0,0,0,0,0,0,0,0,0,0,0,BB72,0)';
      PINUSE='GROUND';
      NO_LOAD_CHECK='Both';
      NO_IO_CHECK='Both';
      NO_ASSERT_CHECK='TRUE';
      NO_DIR_CHECK='TRUE';
      ALLOW_CONNECT='TRUE';
    'VSS'<127>:
      PIN_NUMBER='(0,0,0,0,0,0,0,0,0,0,0,0,BC69,0)';
      PINUSE='GROUND';
      NO_LOAD_CHECK='Both';
      NO_IO_CHECK='Both';
      NO_ASSERT_CHECK='TRUE';
      NO_DIR_CHECK='TRUE';
      ALLOW_CONNECT='TRUE';
    'VSS'<126>:
      PIN_NUMBER='(0,0,0,0,0,0,0,0,0,0,0,0,BC71,0)';
      PINUSE='GROUND';
      NO_LOAD_CHECK='Both';
      NO_IO_CHECK='Both';
      NO_ASSERT_CHECK='TRUE';
      NO_DIR_CHECK='TRUE';
      ALLOW_CONNECT='TRUE';
    'VSS'<125>:
      PIN_NUMBER='(0,0,0,0,0,0,0,0,0,0,0,0,BD24,0)';
      PINUSE='GROUND';
      NO_LOAD_CHECK='Both';
      NO_IO_CHECK='Both';
      NO_ASSERT_CHECK='TRUE';
      NO_DIR_CHECK='TRUE';
      ALLOW_CONNECT='TRUE';
    'VSS'<124>:
      PIN_NUMBER='(0,0,0,0,0,0,0,0,0,0,0,0,BD27,0)';
      PINUSE='GROUND';
      NO_LOAD_CHECK='Both';
      NO_IO_CHECK='Both';
      NO_ASSERT_CHECK='TRUE';
      NO_DIR_CHECK='TRUE';
      ALLOW_CONNECT='TRUE';
    'VSS'<123>:
      PIN_NUMBER='(0,0,0,0,0,0,0,0,0,0,0,0,BD31,0)';
      PINUSE='GROUND';
      NO_LOAD_CHECK='Both';
      NO_IO_CHECK='Both';
      NO_ASSERT_CHECK='TRUE';
      NO_DIR_CHECK='TRUE';
      ALLOW_CONNECT='TRUE';
    'VSS'<122>:
      PIN_NUMBER='(0,0,0,0,0,0,0,0,0,0,0,0,BD35,0)';
      PINUSE='GROUND';
      NO_LOAD_CHECK='Both';
      NO_IO_CHECK='Both';
      NO_ASSERT_CHECK='TRUE';
      NO_DIR_CHECK='TRUE';
      ALLOW_CONNECT='TRUE';
    'VSS'<121>:
      PIN_NUMBER='(0,0,0,0,0,0,0,0,0,0,0,0,BD5,0)';
      PINUSE='GROUND';
      NO_LOAD_CHECK='Both';
      NO_IO_CHECK='Both';
      NO_ASSERT_CHECK='TRUE';
      NO_DIR_CHECK='TRUE';
      ALLOW_CONNECT='TRUE';
    'VSS'<120>:
      PIN_NUMBER='(0,0,0,0,0,0,0,0,0,0,0,0,BD50,0)';
      PINUSE='GROUND';
      NO_LOAD_CHECK='Both';
      NO_IO_CHECK='Both';
      NO_ASSERT_CHECK='TRUE';
      NO_DIR_CHECK='TRUE';
      ALLOW_CONNECT='TRUE';
    'VSS'<119>:
      PIN_NUMBER='(0,0,0,0,0,0,0,0,0,0,0,0,BD54,0)';
      PINUSE='GROUND';
      NO_LOAD_CHECK='Both';
      NO_IO_CHECK='Both';
      NO_ASSERT_CHECK='TRUE';
      NO_DIR_CHECK='TRUE';
      ALLOW_CONNECT='TRUE';
    'VSS'<118>:
      PIN_NUMBER='(0,0,0,0,0,0,0,0,0,0,0,0,BD68,0)';
      PINUSE='GROUND';
      NO_LOAD_CHECK='Both';
      NO_IO_CHECK='Both';
      NO_ASSERT_CHECK='TRUE';
      NO_DIR_CHECK='TRUE';
      ALLOW_CONNECT='TRUE';
    'VSS'<117>:
      PIN_NUMBER='(0,0,0,0,0,0,0,0,0,0,0,0,BE29,0)';
      PINUSE='GROUND';
      NO_LOAD_CHECK='Both';
      NO_IO_CHECK='Both';
      NO_ASSERT_CHECK='TRUE';
      NO_DIR_CHECK='TRUE';
      ALLOW_CONNECT='TRUE';
    'VSS'<116>:
      PIN_NUMBER='(0,0,0,0,0,0,0,0,0,0,0,0,BE33,0)';
      PINUSE='GROUND';
      NO_LOAD_CHECK='Both';
      NO_IO_CHECK='Both';
      NO_ASSERT_CHECK='TRUE';
      NO_DIR_CHECK='TRUE';
      ALLOW_CONNECT='TRUE';
    'VSS'<115>:
      PIN_NUMBER='(0,0,0,0,0,0,0,0,0,0,0,0,BE37,0)';
      PINUSE='GROUND';
      NO_LOAD_CHECK='Both';
      NO_IO_CHECK='Both';
      NO_ASSERT_CHECK='TRUE';
      NO_DIR_CHECK='TRUE';
      ALLOW_CONNECT='TRUE';
    'VSS'<114>:
      PIN_NUMBER='(0,0,0,0,0,0,0,0,0,0,0,0,BE56,0)';
      PINUSE='GROUND';
      NO_LOAD_CHECK='Both';
      NO_IO_CHECK='Both';
      NO_ASSERT_CHECK='TRUE';
      NO_DIR_CHECK='TRUE';
      ALLOW_CONNECT='TRUE';
    'VSS'<113>:
      PIN_NUMBER='(0,0,0,0,0,0,0,0,0,0,0,0,BE59,0)';
      PINUSE='GROUND';
      NO_LOAD_CHECK='Both';
      NO_IO_CHECK='Both';
      NO_ASSERT_CHECK='TRUE';
      NO_DIR_CHECK='TRUE';
      ALLOW_CONNECT='TRUE';
    'VSS'<112>:
      PIN_NUMBER='(0,0,0,0,0,0,0,0,0,0,0,0,BE63,0)';
      PINUSE='GROUND';
      NO_LOAD_CHECK='Both';
      NO_IO_CHECK='Both';
      NO_ASSERT_CHECK='TRUE';
      NO_DIR_CHECK='TRUE';
      ALLOW_CONNECT='TRUE';
    'VSS'<111>:
      PIN_NUMBER='(0,0,0,0,0,0,0,0,0,0,0,0,BE66,0)';
      PINUSE='GROUND';
      NO_LOAD_CHECK='Both';
      NO_IO_CHECK='Both';
      NO_ASSERT_CHECK='TRUE';
      NO_DIR_CHECK='TRUE';
      ALLOW_CONNECT='TRUE';
    'VSS'<110>:
      PIN_NUMBER='(0,0,0,0,0,0,0,0,0,0,0,0,BF13,0)';
      PINUSE='GROUND';
      NO_LOAD_CHECK='Both';
      NO_IO_CHECK='Both';
      NO_ASSERT_CHECK='TRUE';
      NO_DIR_CHECK='TRUE';
      ALLOW_CONNECT='TRUE';
    'VSS'<109>:
      PIN_NUMBER='(0,0,0,0,0,0,0,0,0,0,0,0,BF17,0)';
      PINUSE='GROUND';
      NO_LOAD_CHECK='Both';
      NO_IO_CHECK='Both';
      NO_ASSERT_CHECK='TRUE';
      NO_DIR_CHECK='TRUE';
      ALLOW_CONNECT='TRUE';
    'VSS'<108>:
      PIN_NUMBER='(0,0,0,0,0,0,0,0,0,0,0,0,BF54,0)';
      PINUSE='GROUND';
      NO_LOAD_CHECK='Both';
      NO_IO_CHECK='Both';
      NO_ASSERT_CHECK='TRUE';
      NO_DIR_CHECK='TRUE';
      ALLOW_CONNECT='TRUE';
    'VSS'<107>:
      PIN_NUMBER='(0,0,0,0,0,0,0,0,0,0,0,0,BG44,0)';
      PINUSE='GROUND';
      NO_LOAD_CHECK='Both';
      NO_IO_CHECK='Both';
      NO_ASSERT_CHECK='TRUE';
      NO_DIR_CHECK='TRUE';
      ALLOW_CONNECT='TRUE';
    'VSS'<106>:
      PIN_NUMBER='(0,0,0,0,0,0,0,0,0,0,0,0,BF20,0)';
      PINUSE='GROUND';
      NO_LOAD_CHECK='Both';
      NO_IO_CHECK='Both';
      NO_ASSERT_CHECK='TRUE';
      NO_DIR_CHECK='TRUE';
      ALLOW_CONNECT='TRUE';
    'VSS'<105>:
      PIN_NUMBER='(0,0,0,0,0,0,0,0,0,0,0,0,BF24,0)';
      PINUSE='GROUND';
      NO_LOAD_CHECK='Both';
      NO_IO_CHECK='Both';
      NO_ASSERT_CHECK='TRUE';
      NO_DIR_CHECK='TRUE';
      ALLOW_CONNECT='TRUE';
    'VSS'<104>:
      PIN_NUMBER='(0,0,0,0,0,0,0,0,0,0,0,0,BF27,0)';
      PINUSE='GROUND';
      NO_LOAD_CHECK='Both';
      NO_IO_CHECK='Both';
      NO_ASSERT_CHECK='TRUE';
      NO_DIR_CHECK='TRUE';
      ALLOW_CONNECT='TRUE';
    'VSS'<103>:
      PIN_NUMBER='(0,0,0,0,0,0,0,0,0,0,0,0,BF38,0)';
      PINUSE='GROUND';
      NO_LOAD_CHECK='Both';
      NO_IO_CHECK='Both';
      NO_ASSERT_CHECK='TRUE';
      NO_DIR_CHECK='TRUE';
      ALLOW_CONNECT='TRUE';
    'VSS'<102>:
      PIN_NUMBER='(0,0,0,0,0,0,0,0,0,0,0,0,BF42,0)';
      PINUSE='GROUND';
      NO_LOAD_CHECK='Both';
      NO_IO_CHECK='Both';
      NO_ASSERT_CHECK='TRUE';
      NO_DIR_CHECK='TRUE';
      ALLOW_CONNECT='TRUE';
    'VSS'<101>:
      PIN_NUMBER='(0,0,0,0,0,0,0,0,0,0,0,0,BF5,0)';
      PINUSE='GROUND';
      NO_LOAD_CHECK='Both';
      NO_IO_CHECK='Both';
      NO_ASSERT_CHECK='TRUE';
      NO_DIR_CHECK='TRUE';
      ALLOW_CONNECT='TRUE';
    'VSS'<100>:
      PIN_NUMBER='(0,0,0,0,0,0,0,0,0,0,0,0,BF50,0)';
      PINUSE='GROUND';
      NO_LOAD_CHECK='Both';
      NO_IO_CHECK='Both';
      NO_ASSERT_CHECK='TRUE';
      NO_DIR_CHECK='TRUE';
      ALLOW_CONNECT='TRUE';
    'VSS'<99>:
      PIN_NUMBER='(0,0,0,0,0,0,0,0,0,0,0,0,BF58,0)';
      PINUSE='GROUND';
      NO_LOAD_CHECK='Both';
      NO_IO_CHECK='Both';
      NO_ASSERT_CHECK='TRUE';
      NO_DIR_CHECK='TRUE';
      ALLOW_CONNECT='TRUE';
    'VSS'<98>:
      PIN_NUMBER='(0,0,0,0,0,0,0,0,0,0,0,0,BF61,0)';
      PINUSE='GROUND';
      NO_LOAD_CHECK='Both';
      NO_IO_CHECK='Both';
      NO_ASSERT_CHECK='TRUE';
      NO_DIR_CHECK='TRUE';
      ALLOW_CONNECT='TRUE';
    'VSS'<97>:
      PIN_NUMBER='(0,0,0,0,0,0,0,0,0,0,0,0,BF65,0)';
      PINUSE='GROUND';
      NO_LOAD_CHECK='Both';
      NO_IO_CHECK='Both';
      NO_ASSERT_CHECK='TRUE';
      NO_DIR_CHECK='TRUE';
      ALLOW_CONNECT='TRUE';
    'VSS'<96>:
      PIN_NUMBER='(0,0,0,0,0,0,0,0,0,0,0,0,BF68,0)';
      PINUSE='GROUND';
      NO_LOAD_CHECK='Both';
      NO_IO_CHECK='Both';
      NO_ASSERT_CHECK='TRUE';
      NO_DIR_CHECK='TRUE';
      ALLOW_CONNECT='TRUE';
    'VSS'<95>:
      PIN_NUMBER='(0,0,0,0,0,0,0,0,0,0,0,0,BF9,0)';
      PINUSE='GROUND';
      NO_LOAD_CHECK='Both';
      NO_IO_CHECK='Both';
      NO_ASSERT_CHECK='TRUE';
      NO_DIR_CHECK='TRUE';
      ALLOW_CONNECT='TRUE';
    'VSS'<94>:
      PIN_NUMBER='(0,0,0,0,0,0,0,0,0,0,0,0,BG33,0)';
      PINUSE='GROUND';
      NO_LOAD_CHECK='Both';
      NO_IO_CHECK='Both';
      NO_ASSERT_CHECK='TRUE';
      NO_DIR_CHECK='TRUE';
      ALLOW_CONNECT='TRUE';
    'VSS'<93>:
      PIN_NUMBER='(0,0,0,0,0,0,0,0,0,0,0,0,BG48,0)';
      PINUSE='GROUND';
      NO_LOAD_CHECK='Both';
      NO_IO_CHECK='Both';
      NO_ASSERT_CHECK='TRUE';
      NO_DIR_CHECK='TRUE';
      ALLOW_CONNECT='TRUE';
    'VSS'<92>:
      PIN_NUMBER='(0,0,0,0,0,0,0,0,0,0,0,0,BG59,0)';
      PINUSE='GROUND';
      NO_LOAD_CHECK='Both';
      NO_IO_CHECK='Both';
      NO_ASSERT_CHECK='TRUE';
      NO_DIR_CHECK='TRUE';
      ALLOW_CONNECT='TRUE';
    'VSS'<91>:
      PIN_NUMBER='(0,0,0,0,0,0,0,0,0,0,0,0,BG63,0)';
      PINUSE='GROUND';
      NO_LOAD_CHECK='Both';
      NO_IO_CHECK='Both';
      NO_ASSERT_CHECK='TRUE';
      NO_DIR_CHECK='TRUE';
      ALLOW_CONNECT='TRUE';
    'VSS'<90>:
      PIN_NUMBER='(0,0,0,0,0,0,0,0,0,0,0,0,BH27,0)';
      PINUSE='GROUND';
      NO_LOAD_CHECK='Both';
      NO_IO_CHECK='Both';
      NO_ASSERT_CHECK='TRUE';
      NO_DIR_CHECK='TRUE';
      ALLOW_CONNECT='TRUE';
    'VSS'<89>:
      PIN_NUMBER='(0,0,0,0,0,0,0,0,0,0,0,0,BH38,0)';
      PINUSE='GROUND';
      NO_LOAD_CHECK='Both';
      NO_IO_CHECK='Both';
      NO_ASSERT_CHECK='TRUE';
      NO_DIR_CHECK='TRUE';
      ALLOW_CONNECT='TRUE';
    'VSS'<88>:
      PIN_NUMBER='(0,0,0,0,0,0,0,0,0,0,0,0,BH42,0)';
      PINUSE='GROUND';
      NO_LOAD_CHECK='Both';
      NO_IO_CHECK='Both';
      NO_ASSERT_CHECK='TRUE';
      NO_DIR_CHECK='TRUE';
      ALLOW_CONNECT='TRUE';
    'VSS'<87>:
      PIN_NUMBER='(0,0,0,0,0,0,0,0,0,0,0,0,BH46,0)';
      PINUSE='GROUND';
      NO_LOAD_CHECK='Both';
      NO_IO_CHECK='Both';
      NO_ASSERT_CHECK='TRUE';
      NO_DIR_CHECK='TRUE';
      ALLOW_CONNECT='TRUE';
    'VSS'<86>:
      PIN_NUMBER='(0,0,0,0,0,0,0,0,0,0,0,0,BH54,0)';
      PINUSE='GROUND';
      NO_LOAD_CHECK='Both';
      NO_IO_CHECK='Both';
      NO_ASSERT_CHECK='TRUE';
      NO_DIR_CHECK='TRUE';
      ALLOW_CONNECT='TRUE';
    'VSS'<85>:
      PIN_NUMBER='(0,0,0,0,0,0,0,0,0,0,0,0,BJ1,0)';
      PINUSE='GROUND';
      NO_LOAD_CHECK='Both';
      NO_IO_CHECK='Both';
      NO_ASSERT_CHECK='TRUE';
      NO_DIR_CHECK='TRUE';
      ALLOW_CONNECT='TRUE';
    'VSS'<84>:
      PIN_NUMBER='(0,0,0,0,0,0,0,0,0,0,0,0,BJ11,0)';
      PINUSE='GROUND';
      NO_LOAD_CHECK='Both';
      NO_IO_CHECK='Both';
      NO_ASSERT_CHECK='TRUE';
      NO_DIR_CHECK='TRUE';
      ALLOW_CONNECT='TRUE';
    'VSS'<83>:
      PIN_NUMBER='(0,0,0,0,0,0,0,0,0,0,0,0,BJ5,0)';
      PINUSE='GROUND';
      NO_LOAD_CHECK='Both';
      NO_IO_CHECK='Both';
      NO_ASSERT_CHECK='TRUE';
      NO_DIR_CHECK='TRUE';
      ALLOW_CONNECT='TRUE';
    'VSS'<82>:
      PIN_NUMBER='(0,0,0,0,0,0,0,0,0,0,0,0,BJ7,0)';
      PINUSE='GROUND';
      NO_LOAD_CHECK='Both';
      NO_IO_CHECK='Both';
      NO_ASSERT_CHECK='TRUE';
      NO_DIR_CHECK='TRUE';
      ALLOW_CONNECT='TRUE';
    'VSS'<81>:
      PIN_NUMBER='(0,0,0,0,0,0,0,0,0,0,0,0,BJ15,0)';
      PINUSE='GROUND';
      NO_LOAD_CHECK='Both';
      NO_IO_CHECK='Both';
      NO_ASSERT_CHECK='TRUE';
      NO_DIR_CHECK='TRUE';
      ALLOW_CONNECT='TRUE';
    'VSS'<80>:
      PIN_NUMBER='(0,0,0,0,0,0,0,0,0,0,0,0,BJ18,0)';
      PINUSE='GROUND';
      NO_LOAD_CHECK='Both';
      NO_IO_CHECK='Both';
      NO_ASSERT_CHECK='TRUE';
      NO_DIR_CHECK='TRUE';
      ALLOW_CONNECT='TRUE';
    'VSS'<79>:
      PIN_NUMBER='(0,0,0,0,0,0,0,0,0,0,0,0,BJ26,0)';
      PINUSE='GROUND';
      NO_LOAD_CHECK='Both';
      NO_IO_CHECK='Both';
      NO_ASSERT_CHECK='TRUE';
      NO_DIR_CHECK='TRUE';
      ALLOW_CONNECT='TRUE';
    'VSS'<78>:
      PIN_NUMBER='(0,0,0,0,0,0,0,0,0,0,0,0,BJ3,0)';
      PINUSE='GROUND';
      NO_LOAD_CHECK='Both';
      NO_IO_CHECK='Both';
      NO_ASSERT_CHECK='TRUE';
      NO_DIR_CHECK='TRUE';
      ALLOW_CONNECT='TRUE';
    'VSS'<77>:
      PIN_NUMBER='(0,0,0,0,0,0,0,0,0,0,0,0,BJ33,0)';
      PINUSE='GROUND';
      NO_LOAD_CHECK='Both';
      NO_IO_CHECK='Both';
      NO_ASSERT_CHECK='TRUE';
      NO_DIR_CHECK='TRUE';
      ALLOW_CONNECT='TRUE';
    'VSS'<76>:
      PIN_NUMBER='(0,0,0,0,0,0,0,0,0,0,0,0,BJ52,0)';
      PINUSE='GROUND';
      NO_LOAD_CHECK='Both';
      NO_IO_CHECK='Both';
      NO_ASSERT_CHECK='TRUE';
      NO_DIR_CHECK='TRUE';
      ALLOW_CONNECT='TRUE';
    'VSS'<75>:
      PIN_NUMBER='(0,0,0,0,0,0,0,0,0,0,0,0,BJ68,0)';
      PINUSE='GROUND';
      NO_LOAD_CHECK='Both';
      NO_IO_CHECK='Both';
      NO_ASSERT_CHECK='TRUE';
      NO_DIR_CHECK='TRUE';
      ALLOW_CONNECT='TRUE';
    'VSS'<74>:
      PIN_NUMBER='(0,0,0,0,0,0,0,0,0,0,0,0,0,BK24)';
      PINUSE='GROUND';
      NO_LOAD_CHECK='Both';
      NO_IO_CHECK='Both';
      NO_ASSERT_CHECK='TRUE';
      NO_DIR_CHECK='TRUE';
      ALLOW_CONNECT='TRUE';
    'VSS'<73>:
      PIN_NUMBER='(0,0,0,0,0,0,0,0,0,0,0,0,0,BK27)';
      PINUSE='GROUND';
      NO_LOAD_CHECK='Both';
      NO_IO_CHECK='Both';
      NO_ASSERT_CHECK='TRUE';
      NO_DIR_CHECK='TRUE';
      ALLOW_CONNECT='TRUE';
    'VSS'<72>:
      PIN_NUMBER='(0,0,0,0,0,0,0,0,0,0,0,0,0,BK31)';
      PINUSE='GROUND';
      NO_LOAD_CHECK='Both';
      NO_IO_CHECK='Both';
      NO_ASSERT_CHECK='TRUE';
      NO_DIR_CHECK='TRUE';
      ALLOW_CONNECT='TRUE';
    'VSS'<71>:
      PIN_NUMBER='(0,0,0,0,0,0,0,0,0,0,0,0,0,BK35)';
      PINUSE='GROUND';
      NO_LOAD_CHECK='Both';
      NO_IO_CHECK='Both';
      NO_ASSERT_CHECK='TRUE';
      NO_DIR_CHECK='TRUE';
      ALLOW_CONNECT='TRUE';
    'VSS'<70>:
      PIN_NUMBER='(0,0,0,0,0,0,0,0,0,0,0,0,0,BK38)';
      PINUSE='GROUND';
      NO_LOAD_CHECK='Both';
      NO_IO_CHECK='Both';
      NO_ASSERT_CHECK='TRUE';
      NO_DIR_CHECK='TRUE';
      ALLOW_CONNECT='TRUE';
    'VSS'<69>:
      PIN_NUMBER='(0,0,0,0,0,0,0,0,0,0,0,0,0,BK42)';
      PINUSE='GROUND';
      NO_LOAD_CHECK='Both';
      NO_IO_CHECK='Both';
      NO_ASSERT_CHECK='TRUE';
      NO_DIR_CHECK='TRUE';
      ALLOW_CONNECT='TRUE';
    'VSS'<68>:
      PIN_NUMBER='(0,0,0,0,0,0,0,0,0,0,0,0,0,BK50)';
      PINUSE='GROUND';
      NO_LOAD_CHECK='Both';
      NO_IO_CHECK='Both';
      NO_ASSERT_CHECK='TRUE';
      NO_DIR_CHECK='TRUE';
      ALLOW_CONNECT='TRUE';
    'VSS'<67>:
      PIN_NUMBER='(0,0,0,0,0,0,0,0,0,0,0,0,0,BL22)';
      PINUSE='GROUND';
      NO_LOAD_CHECK='Both';
      NO_IO_CHECK='Both';
      NO_ASSERT_CHECK='TRUE';
      NO_DIR_CHECK='TRUE';
      ALLOW_CONNECT='TRUE';
    'VSS'<66>:
      PIN_NUMBER='(0,0,0,0,0,0,0,0,0,0,0,0,0,BL40)';
      PINUSE='GROUND';
      NO_LOAD_CHECK='Both';
      NO_IO_CHECK='Both';
      NO_ASSERT_CHECK='TRUE';
      NO_DIR_CHECK='TRUE';
      ALLOW_CONNECT='TRUE';
    'VSS'<65>:
      PIN_NUMBER='(0,0,0,0,0,0,0,0,0,0,0,0,0,BL68)';
      PINUSE='GROUND';
      NO_LOAD_CHECK='Both';
      NO_IO_CHECK='Both';
      NO_ASSERT_CHECK='TRUE';
      NO_DIR_CHECK='TRUE';
      ALLOW_CONNECT='TRUE';
    'VSS'<64>:
      PIN_NUMBER='(0,0,0,0,0,0,0,0,0,0,0,0,0,BL37)';
      PINUSE='GROUND';
      NO_LOAD_CHECK='Both';
      NO_IO_CHECK='Both';
      NO_ASSERT_CHECK='TRUE';
      NO_DIR_CHECK='TRUE';
      ALLOW_CONNECT='TRUE';
    'VSS'<63>:
      PIN_NUMBER='(0,0,0,0,0,0,0,0,0,0,0,0,0,BL5)';
      PINUSE='GROUND';
      NO_LOAD_CHECK='Both';
      NO_IO_CHECK='Both';
      NO_ASSERT_CHECK='TRUE';
      NO_DIR_CHECK='TRUE';
      ALLOW_CONNECT='TRUE';
    'VSS'<62>:
      PIN_NUMBER='(0,0,0,0,0,0,0,0,0,0,0,0,0,BL63)';
      PINUSE='GROUND';
      NO_LOAD_CHECK='Both';
      NO_IO_CHECK='Both';
      NO_ASSERT_CHECK='TRUE';
      NO_DIR_CHECK='TRUE';
      ALLOW_CONNECT='TRUE';
    'VSS'<61>:
      PIN_NUMBER='(0,0,0,0,0,0,0,0,0,0,0,0,0,BL70)';
      PINUSE='GROUND';
      NO_LOAD_CHECK='Both';
      NO_IO_CHECK='Both';
      NO_ASSERT_CHECK='TRUE';
      NO_DIR_CHECK='TRUE';
      ALLOW_CONNECT='TRUE';
    'VSS'<60>:
      PIN_NUMBER='(0,0,0,0,0,0,0,0,0,0,0,0,0,BL72)';
      PINUSE='GROUND';
      NO_LOAD_CHECK='Both';
      NO_IO_CHECK='Both';
      NO_ASSERT_CHECK='TRUE';
      NO_DIR_CHECK='TRUE';
      ALLOW_CONNECT='TRUE';
    'VSS'<59>:
      PIN_NUMBER='(0,0,0,0,0,0,0,0,0,0,0,0,0,BM13)';
      PINUSE='GROUND';
      NO_LOAD_CHECK='Both';
      NO_IO_CHECK='Both';
      NO_ASSERT_CHECK='TRUE';
      NO_DIR_CHECK='TRUE';
      ALLOW_CONNECT='TRUE';
    'VSS'<58>:
      PIN_NUMBER='(0,0,0,0,0,0,0,0,0,0,0,0,0,BM17)';
      PINUSE='GROUND';
      NO_LOAD_CHECK='Both';
      NO_IO_CHECK='Both';
      NO_ASSERT_CHECK='TRUE';
      NO_DIR_CHECK='TRUE';
      ALLOW_CONNECT='TRUE';
    'VSS'<57>:
      PIN_NUMBER='(0,0,0,0,0,0,0,0,0,0,0,0,0,BN37)';
      PINUSE='GROUND';
      NO_LOAD_CHECK='Both';
      NO_IO_CHECK='Both';
      NO_ASSERT_CHECK='TRUE';
      NO_DIR_CHECK='TRUE';
      ALLOW_CONNECT='TRUE';
    'VSS'<56>:
      PIN_NUMBER='(0,0,0,0,0,0,0,0,0,0,0,0,0,BM46)';
      PINUSE='GROUND';
      NO_LOAD_CHECK='Both';
      NO_IO_CHECK='Both';
      NO_ASSERT_CHECK='TRUE';
      NO_DIR_CHECK='TRUE';
      ALLOW_CONNECT='TRUE';
    'VSS'<55>:
      PIN_NUMBER='(0,0,0,0,0,0,0,0,0,0,0,0,0,BM50)';
      PINUSE='GROUND';
      NO_LOAD_CHECK='Both';
      NO_IO_CHECK='Both';
      NO_ASSERT_CHECK='TRUE';
      NO_DIR_CHECK='TRUE';
      ALLOW_CONNECT='TRUE';
    'VSS'<54>:
      PIN_NUMBER='(0,0,0,0,0,0,0,0,0,0,0,0,0,BM58)';
      PINUSE='GROUND';
      NO_LOAD_CHECK='Both';
      NO_IO_CHECK='Both';
      NO_ASSERT_CHECK='TRUE';
      NO_DIR_CHECK='TRUE';
      ALLOW_CONNECT='TRUE';
    'VSS'<53>:
      PIN_NUMBER='(0,0,0,0,0,0,0,0,0,0,0,0,0,BM69)';
      PINUSE='GROUND';
      NO_LOAD_CHECK='Both';
      NO_IO_CHECK='Both';
      NO_ASSERT_CHECK='TRUE';
      NO_DIR_CHECK='TRUE';
      ALLOW_CONNECT='TRUE';
    'VSS'<52>:
      PIN_NUMBER='(0,0,0,0,0,0,0,0,0,0,0,0,0,BM71)';
      PINUSE='GROUND';
      NO_LOAD_CHECK='Both';
      NO_IO_CHECK='Both';
      NO_ASSERT_CHECK='TRUE';
      NO_DIR_CHECK='TRUE';
      ALLOW_CONNECT='TRUE';
    'VSS'<51>:
      PIN_NUMBER='(0,0,0,0,0,0,0,0,0,0,0,0,0,BM9)';
      PINUSE='GROUND';
      NO_LOAD_CHECK='Both';
      NO_IO_CHECK='Both';
      NO_ASSERT_CHECK='TRUE';
      NO_DIR_CHECK='TRUE';
      ALLOW_CONNECT='TRUE';
    'VSS'<50>:
      PIN_NUMBER='(0,0,0,0,0,0,0,0,0,0,0,0,0,BN22)';
      PINUSE='GROUND';
      NO_LOAD_CHECK='Both';
      NO_IO_CHECK='Both';
      NO_ASSERT_CHECK='TRUE';
      NO_DIR_CHECK='TRUE';
      ALLOW_CONNECT='TRUE';
    'VSS'<49>:
      PIN_NUMBER='(0,0,0,0,0,0,0,0,0,0,0,0,0,BN59)';
      PINUSE='GROUND';
      NO_LOAD_CHECK='Both';
      NO_IO_CHECK='Both';
      NO_ASSERT_CHECK='TRUE';
      NO_DIR_CHECK='TRUE';
      ALLOW_CONNECT='TRUE';
    'VSS'<48>:
      PIN_NUMBER='(0,0,0,0,0,0,0,0,0,0,0,0,0,BN5)';
      PINUSE='GROUND';
      NO_LOAD_CHECK='Both';
      NO_IO_CHECK='Both';
      NO_ASSERT_CHECK='TRUE';
      NO_DIR_CHECK='TRUE';
      ALLOW_CONNECT='TRUE';
    'VSS'<47>:
      PIN_NUMBER='(0,0,0,0,0,0,0,0,0,0,0,0,0,BN52)';
      PINUSE='GROUND';
      NO_LOAD_CHECK='Both';
      NO_IO_CHECK='Both';
      NO_ASSERT_CHECK='TRUE';
      NO_DIR_CHECK='TRUE';
      ALLOW_CONNECT='TRUE';
    'VSS'<46>:
      PIN_NUMBER='(0,0,0,0,0,0,0,0,0,0,0,0,0,BN66)';
      PINUSE='GROUND';
      NO_LOAD_CHECK='Both';
      NO_IO_CHECK='Both';
      NO_ASSERT_CHECK='TRUE';
      NO_DIR_CHECK='TRUE';
      ALLOW_CONNECT='TRUE';
    'VSS'<45>:
      PIN_NUMBER='(0,0,0,0,0,0,0,0,0,0,0,0,0,BR20)';
      PINUSE='GROUND';
      NO_LOAD_CHECK='Both';
      NO_IO_CHECK='Both';
      NO_ASSERT_CHECK='TRUE';
      NO_DIR_CHECK='TRUE';
      ALLOW_CONNECT='TRUE';
    'VSS'<44>:
      PIN_NUMBER='(0,0,0,0,0,0,0,0,0,0,0,0,0,BR50)';
      PINUSE='GROUND';
      NO_LOAD_CHECK='Both';
      NO_IO_CHECK='Both';
      NO_ASSERT_CHECK='TRUE';
      NO_DIR_CHECK='TRUE';
      ALLOW_CONNECT='TRUE';
    'VSS'<43>:
      PIN_NUMBER='(0,0,0,0,0,0,0,0,0,0,0,0,0,BT8)';
      PINUSE='GROUND';
      NO_LOAD_CHECK='Both';
      NO_IO_CHECK='Both';
      NO_ASSERT_CHECK='TRUE';
      NO_DIR_CHECK='TRUE';
      ALLOW_CONNECT='TRUE';
    'VSS'<42>:
      PIN_NUMBER='(0,0,0,0,0,0,0,0,0,0,0,0,0,BR54)';
      PINUSE='GROUND';
      NO_LOAD_CHECK='Both';
      NO_IO_CHECK='Both';
      NO_ASSERT_CHECK='TRUE';
      NO_DIR_CHECK='TRUE';
      ALLOW_CONNECT='TRUE';
    'VSS'<41>:
      PIN_NUMBER='(0,0,0,0,0,0,0,0,0,0,0,0,0,BR58)';
      PINUSE='GROUND';
      NO_LOAD_CHECK='Both';
      NO_IO_CHECK='Both';
      NO_ASSERT_CHECK='TRUE';
      NO_DIR_CHECK='TRUE';
      ALLOW_CONNECT='TRUE';
    'VSS'<40>:
      PIN_NUMBER='(0,0,0,0,0,0,0,0,0,0,0,0,0,BR6)';
      PINUSE='GROUND';
      NO_LOAD_CHECK='Both';
      NO_IO_CHECK='Both';
      NO_ASSERT_CHECK='TRUE';
      NO_DIR_CHECK='TRUE';
      ALLOW_CONNECT='TRUE';
    'VSS'<39>:
      PIN_NUMBER='(0,0,0,0,0,0,0,0,0,0,0,0,0,BT66)';
      PINUSE='GROUND';
      NO_LOAD_CHECK='Both';
      NO_IO_CHECK='Both';
      NO_ASSERT_CHECK='TRUE';
      NO_DIR_CHECK='TRUE';
      ALLOW_CONNECT='TRUE';
    'VSS'<38>:
      PIN_NUMBER='(0,0,0,0,0,0,0,0,0,0,0,0,0,BU13)';
      PINUSE='GROUND';
      NO_LOAD_CHECK='Both';
      NO_IO_CHECK='Both';
      NO_ASSERT_CHECK='TRUE';
      NO_DIR_CHECK='TRUE';
      ALLOW_CONNECT='TRUE';
    'VSS'<37>:
      PIN_NUMBER='(0,0,0,0,0,0,0,0,0,0,0,0,0,BU11)';
      PINUSE='GROUND';
      NO_LOAD_CHECK='Both';
      NO_IO_CHECK='Both';
      NO_ASSERT_CHECK='TRUE';
      NO_DIR_CHECK='TRUE';
      ALLOW_CONNECT='TRUE';
    'VSS'<36>:
      PIN_NUMBER='(0,0,0,0,0,0,0,0,0,0,0,0,0,BV49)';
      PINUSE='GROUND';
      NO_LOAD_CHECK='Both';
      NO_IO_CHECK='Both';
      NO_ASSERT_CHECK='TRUE';
      NO_DIR_CHECK='TRUE';
      ALLOW_CONNECT='TRUE';
    'VSS'<35>:
      PIN_NUMBER='(0,0,0,0,0,0,0,0,0,0,0,0,0,BU15)';
      PINUSE='GROUND';
      NO_LOAD_CHECK='Both';
      NO_IO_CHECK='Both';
      NO_ASSERT_CHECK='TRUE';
      NO_DIR_CHECK='TRUE';
      ALLOW_CONNECT='TRUE';
    'VSS'<34>:
      PIN_NUMBER='(0,0,0,0,0,0,0,0,0,0,0,0,0,BU18)';
      PINUSE='GROUND';
      NO_LOAD_CHECK='Both';
      NO_IO_CHECK='Both';
      NO_ASSERT_CHECK='TRUE';
      NO_DIR_CHECK='TRUE';
      ALLOW_CONNECT='TRUE';
    'VSS'<33>:
      PIN_NUMBER='(0,0,0,0,0,0,0,0,0,0,0,0,0,BU20)';
      PINUSE='GROUND';
      NO_LOAD_CHECK='Both';
      NO_IO_CHECK='Both';
      NO_ASSERT_CHECK='TRUE';
      NO_DIR_CHECK='TRUE';
      ALLOW_CONNECT='TRUE';
    'VSS'<32>:
      PIN_NUMBER='(0,0,0,0,0,0,0,0,0,0,0,0,0,BU22)';
      PINUSE='GROUND';
      NO_LOAD_CHECK='Both';
      NO_IO_CHECK='Both';
      NO_ASSERT_CHECK='TRUE';
      NO_DIR_CHECK='TRUE';
      ALLOW_CONNECT='TRUE';
    'VSS'<31>:
      PIN_NUMBER='(0,0,0,0,0,0,0,0,0,0,0,0,0,BU24)';
      PINUSE='GROUND';
      NO_LOAD_CHECK='Both';
      NO_IO_CHECK='Both';
      NO_ASSERT_CHECK='TRUE';
      NO_DIR_CHECK='TRUE';
      ALLOW_CONNECT='TRUE';
    'VSS'<30>:
      PIN_NUMBER='(0,0,0,0,0,0,0,0,0,0,0,0,0,BU26)';
      PINUSE='GROUND';
      NO_LOAD_CHECK='Both';
      NO_IO_CHECK='Both';
      NO_ASSERT_CHECK='TRUE';
      NO_DIR_CHECK='TRUE';
      ALLOW_CONNECT='TRUE';
    'VSS'<29>:
      PIN_NUMBER='(0,0,0,0,0,0,0,0,0,0,0,0,0,BU28)';
      PINUSE='GROUND';
      NO_LOAD_CHECK='Both';
      NO_IO_CHECK='Both';
      NO_ASSERT_CHECK='TRUE';
      NO_DIR_CHECK='TRUE';
      ALLOW_CONNECT='TRUE';
    'VSS'<28>:
      PIN_NUMBER='(0,0,0,0,0,0,0,0,0,0,0,0,0,BU30)';
      PINUSE='GROUND';
      NO_LOAD_CHECK='Both';
      NO_IO_CHECK='Both';
      NO_ASSERT_CHECK='TRUE';
      NO_DIR_CHECK='TRUE';
      ALLOW_CONNECT='TRUE';
    'VSS'<27>:
      PIN_NUMBER='(0,0,0,0,0,0,0,0,0,0,0,0,0,BU32)';
      PINUSE='GROUND';
      NO_LOAD_CHECK='Both';
      NO_IO_CHECK='Both';
      NO_ASSERT_CHECK='TRUE';
      NO_DIR_CHECK='TRUE';
      ALLOW_CONNECT='TRUE';
    'VSS'<26>:
      PIN_NUMBER='(0,0,0,0,0,0,0,0,0,0,0,0,0,BU34)';
      PINUSE='GROUND';
      NO_LOAD_CHECK='Both';
      NO_IO_CHECK='Both';
      NO_ASSERT_CHECK='TRUE';
      NO_DIR_CHECK='TRUE';
      ALLOW_CONNECT='TRUE';
    'VSS'<25>:
      PIN_NUMBER='(0,0,0,0,0,0,0,0,0,0,0,0,0,BU37)';
      PINUSE='GROUND';
      NO_LOAD_CHECK='Both';
      NO_IO_CHECK='Both';
      NO_ASSERT_CHECK='TRUE';
      NO_DIR_CHECK='TRUE';
      ALLOW_CONNECT='TRUE';
    'VSS'<24>:
      PIN_NUMBER='(0,0,0,0,0,0,0,0,0,0,0,0,0,BU39)';
      PINUSE='GROUND';
      NO_LOAD_CHECK='Both';
      NO_IO_CHECK='Both';
      NO_ASSERT_CHECK='TRUE';
      NO_DIR_CHECK='TRUE';
      ALLOW_CONNECT='TRUE';
    'VSS'<23>:
      PIN_NUMBER='(0,0,0,0,0,0,0,0,0,0,0,0,0,BU41)';
      PINUSE='GROUND';
      NO_LOAD_CHECK='Both';
      NO_IO_CHECK='Both';
      NO_ASSERT_CHECK='TRUE';
      NO_DIR_CHECK='TRUE';
      ALLOW_CONNECT='TRUE';
    'VSS'<22>:
      PIN_NUMBER='(0,0,0,0,0,0,0,0,0,0,0,0,0,BU43)';
      PINUSE='GROUND';
      NO_LOAD_CHECK='Both';
      NO_IO_CHECK='Both';
      NO_ASSERT_CHECK='TRUE';
      NO_DIR_CHECK='TRUE';
      ALLOW_CONNECT='TRUE';
    'VSS'<21>:
      PIN_NUMBER='(0,0,0,0,0,0,0,0,0,0,0,0,0,BU45)';
      PINUSE='GROUND';
      NO_LOAD_CHECK='Both';
      NO_IO_CHECK='Both';
      NO_ASSERT_CHECK='TRUE';
      NO_DIR_CHECK='TRUE';
      ALLOW_CONNECT='TRUE';
    'VSS'<20>:
      PIN_NUMBER='(0,0,0,0,0,0,0,0,0,0,0,0,0,BU48)';
      PINUSE='GROUND';
      NO_LOAD_CHECK='Both';
      NO_IO_CHECK='Both';
      NO_ASSERT_CHECK='TRUE';
      NO_DIR_CHECK='TRUE';
      ALLOW_CONNECT='TRUE';
    'VSS'<19>:
      PIN_NUMBER='(0,0,0,0,0,0,0,0,0,0,0,0,0,BU50)';
      PINUSE='GROUND';
      NO_LOAD_CHECK='Both';
      NO_IO_CHECK='Both';
      NO_ASSERT_CHECK='TRUE';
      NO_DIR_CHECK='TRUE';
      ALLOW_CONNECT='TRUE';
    'VSS'<18>:
      PIN_NUMBER='(0,0,0,0,0,0,0,0,0,0,0,0,0,BU52)';
      PINUSE='GROUND';
      NO_LOAD_CHECK='Both';
      NO_IO_CHECK='Both';
      NO_ASSERT_CHECK='TRUE';
      NO_DIR_CHECK='TRUE';
      ALLOW_CONNECT='TRUE';
    'VSS'<17>:
      PIN_NUMBER='(0,0,0,0,0,0,0,0,0,0,0,0,0,BU54)';
      PINUSE='GROUND';
      NO_LOAD_CHECK='Both';
      NO_IO_CHECK='Both';
      NO_ASSERT_CHECK='TRUE';
      NO_DIR_CHECK='TRUE';
      ALLOW_CONNECT='TRUE';
    'VSS'<16>:
      PIN_NUMBER='(0,0,0,0,0,0,0,0,0,0,0,0,0,BU57)';
      PINUSE='GROUND';
      NO_LOAD_CHECK='Both';
      NO_IO_CHECK='Both';
      NO_ASSERT_CHECK='TRUE';
      NO_DIR_CHECK='TRUE';
      ALLOW_CONNECT='TRUE';
    'VSS'<15>:
      PIN_NUMBER='(0,0,0,0,0,0,0,0,0,0,0,0,0,BU59)';
      PINUSE='GROUND';
      NO_LOAD_CHECK='Both';
      NO_IO_CHECK='Both';
      NO_ASSERT_CHECK='TRUE';
      NO_DIR_CHECK='TRUE';
      ALLOW_CONNECT='TRUE';
    'VSS'<14>:
      PIN_NUMBER='(0,0,0,0,0,0,0,0,0,0,0,0,0,BU61)';
      PINUSE='GROUND';
      NO_LOAD_CHECK='Both';
      NO_IO_CHECK='Both';
      NO_ASSERT_CHECK='TRUE';
      NO_DIR_CHECK='TRUE';
      ALLOW_CONNECT='TRUE';
    'VSS'<13>:
      PIN_NUMBER='(0,0,0,0,0,0,0,0,0,0,0,0,0,BU63)';
      PINUSE='GROUND';
      NO_LOAD_CHECK='Both';
      NO_IO_CHECK='Both';
      NO_ASSERT_CHECK='TRUE';
      NO_DIR_CHECK='TRUE';
      ALLOW_CONNECT='TRUE';
    'VSS'<12>:
      PIN_NUMBER='(0,0,0,0,0,0,0,0,0,0,0,0,0,BU9)';
      PINUSE='GROUND';
      NO_LOAD_CHECK='Both';
      NO_IO_CHECK='Both';
      NO_ASSERT_CHECK='TRUE';
      NO_DIR_CHECK='TRUE';
      ALLOW_CONNECT='TRUE';
    'VSS'<11>:
      PIN_NUMBER='(0,0,0,0,0,0,0,0,0,0,0,0,0,BV40)';
      PINUSE='GROUND';
      NO_LOAD_CHECK='Both';
      NO_IO_CHECK='Both';
      NO_ASSERT_CHECK='TRUE';
      NO_DIR_CHECK='TRUE';
      ALLOW_CONNECT='TRUE';
    'VSS'<10>:
      PIN_NUMBER='(0,0,0,0,0,0,0,0,0,0,0,0,0,BW15)';
      PINUSE='GROUND';
      NO_LOAD_CHECK='Both';
      NO_IO_CHECK='Both';
      NO_ASSERT_CHECK='TRUE';
      NO_DIR_CHECK='TRUE';
      ALLOW_CONNECT='TRUE';
    'VSS'<9>:
      PIN_NUMBER='(0,0,0,0,0,0,0,0,0,0,0,0,0,BW18)';
      PINUSE='GROUND';
      NO_LOAD_CHECK='Both';
      NO_IO_CHECK='Both';
      NO_ASSERT_CHECK='TRUE';
      NO_DIR_CHECK='TRUE';
      ALLOW_CONNECT='TRUE';
    'VSS'<8>:
      PIN_NUMBER='(0,0,0,0,0,0,0,0,0,0,0,0,0,BW26)';
      PINUSE='GROUND';
      NO_LOAD_CHECK='Both';
      NO_IO_CHECK='Both';
      NO_ASSERT_CHECK='TRUE';
      NO_DIR_CHECK='TRUE';
      ALLOW_CONNECT='TRUE';
    'VSS'<7>:
      PIN_NUMBER='(0,0,0,0,0,0,0,0,0,0,0,0,0,BW52)';
      PINUSE='GROUND';
      NO_LOAD_CHECK='Both';
      NO_IO_CHECK='Both';
      NO_ASSERT_CHECK='TRUE';
      NO_DIR_CHECK='TRUE';
      ALLOW_CONNECT='TRUE';
    'VSS'<6>:
      PIN_NUMBER='(0,0,0,0,0,0,0,0,0,0,0,0,0,BY40)';
      PINUSE='GROUND';
      NO_LOAD_CHECK='Both';
      NO_IO_CHECK='Both';
      NO_ASSERT_CHECK='TRUE';
      NO_DIR_CHECK='TRUE';
      ALLOW_CONNECT='TRUE';
    'VSS'<5>:
      PIN_NUMBER='(0,0,0,0,0,0,0,0,0,0,0,0,0,BY49)';
      PINUSE='GROUND';
      NO_LOAD_CHECK='Both';
      NO_IO_CHECK='Both';
      NO_ASSERT_CHECK='TRUE';
      NO_DIR_CHECK='TRUE';
      ALLOW_CONNECT='TRUE';
    'VSS'<4>:
      PIN_NUMBER='(0,0,0,0,0,0,0,0,0,0,0,0,0,CA15)';
      PINUSE='GROUND';
      NO_LOAD_CHECK='Both';
      NO_IO_CHECK='Both';
      NO_ASSERT_CHECK='TRUE';
      NO_DIR_CHECK='TRUE';
      ALLOW_CONNECT='TRUE';
    'VSS'<3>:
      PIN_NUMBER='(0,0,0,0,0,0,0,0,0,0,0,0,0,CA18)';
      PINUSE='GROUND';
      NO_LOAD_CHECK='Both';
      NO_IO_CHECK='Both';
      NO_ASSERT_CHECK='TRUE';
      NO_DIR_CHECK='TRUE';
      ALLOW_CONNECT='TRUE';
    'VSS'<2>:
      PIN_NUMBER='(0,0,0,0,0,0,0,0,0,0,0,0,0,CA26)';
      PINUSE='GROUND';
      NO_LOAD_CHECK='Both';
      NO_IO_CHECK='Both';
      NO_ASSERT_CHECK='TRUE';
      NO_DIR_CHECK='TRUE';
      ALLOW_CONNECT='TRUE';
    'VSS'<1>:
      PIN_NUMBER='(0,0,0,0,0,0,0,0,0,0,0,0,0,CA50)';
      PINUSE='GROUND';
      NO_LOAD_CHECK='Both';
      NO_IO_CHECK='Both';
      NO_ASSERT_CHECK='TRUE';
      NO_DIR_CHECK='TRUE';
      ALLOW_CONNECT='TRUE';
    'VSS'<0>:
      PIN_NUMBER='(0,0,0,0,0,0,0,0,0,0,0,0,0,CA52)';
      PINUSE='GROUND';
      NO_LOAD_CHECK='Both';
      NO_IO_CHECK='Both';
      NO_ASSERT_CHECK='TRUE';
      NO_DIR_CHECK='TRUE';
      ALLOW_CONNECT='TRUE';
    'WAKE_N':
      PIN_NUMBER='(0,0,0,0,K9,0,0,0,0,0,0,0,0,0)';
      BIDIRECTIONAL='TRUE';
      INPUT_LOAD='(-0.01,0.01)';
      OUTPUT_LOAD='(1.0,-1.0)';
    'XCLK_BIASREF':
      PIN_NUMBER='(G44,0,0,0,0,0,0,0,0,0,0,0,0,0)';
      BIDIRECTIONAL='TRUE';
      INPUT_LOAD='(-0.01,0.01)';
      OUTPUT_LOAD='(1.0,-1.0)';
    'XTAL_IN':
      PIN_NUMBER='(B35,0,0,0,0,0,0,0,0,0,0,0,0,0)';
      BIDIRECTIONAL='TRUE';
      INPUT_LOAD='(-0.01,0.01)';
      OUTPUT_LOAD='(1.0,-1.0)';
    'XTAL_OUT':
      PIN_NUMBER='(D35,0,0,0,0,0,0,0,0,0,0,0,0,0)';
      BIDIRECTIONAL='TRUE';
      INPUT_LOAD='(-0.01,0.01)';
      OUTPUT_LOAD='(1.0,-1.0)';
  end_pin;
  body
    PART_NAME='LBG_CORE_QAT_EXT_D';
    PHYS_DES_PREFIX='U';
  end_body;
end_primitive;

END.
